FILE_TYPE = MACRO_DRAWING;
SET COLOR_WIRE YELLOW;
SET COLOR_PROP ORANGE;
SET COLOR_DOT WHITE;
SET COLOR_ARC YELLOW;
SET COLOR_BODY GREEN;
SET COLOR_NOTE PURPLE;
SET PROP_DISPLAY VALUE;
SET PAGE_NUMBER P86;
FORCEADD OFFPAGE..2
R 2
(-3800 200);
FORCEPROP 2 LAST $XR0 86 
J 0
(-4024 200);
DISPLAY 0.638298 (-4024 200);
PAINT MONO (-4024 200);
FORCEPROP 2 LAST CDS_LIB standard
J 0
(-3800 200);
PAINT MONO (-3800 200);
DISPLAY INVISIBLE (-3800 200);
FORCEPROP 1 LAST OFFPAGE TRUE
J 2
(-4125 75);
DISPLAY 0.872340 (-4125 75);
DISPLAY INVISIBLE (-4125 75);
FORCEPROP 1 LAST COMMENT_BODY TRUE
J 2
(-3755 105);
DISPLAY 0.872340 (-3755 105);
PAINT GREEN (-3755 105);
DISPLAY INVISIBLE (-3755 105);
FORCEPROP 2 LAST PATH I1
J 0
(-3750 275);
DISPLAY 1.021277 (-3750 275);
DISPLAY INVISIBLE (-3750 275);
FORCEADD OFFPAGE..1
(-3800 1900);
FORCEPROP 2 LAST $XR3 89 
J 0
(-4052 1864);
DISPLAY 0.638298 (-4052 1864);
PAINT MONO (-4052 1864);
FORCEPROP 2 LAST $XR2 88 
J 0
(-4232 1900);
DISPLAY 0.638298 (-4232 1900);
PAINT MONO (-4232 1900);
FORCEPROP 2 LAST $XR1 87 
J 0
(-4142 1900);
DISPLAY 0.638298 (-4142 1900);
PAINT MONO (-4142 1900);
FORCEPROP 2 LAST $XR0 129 
J 0
(-4052 1900);
DISPLAY 0.638298 (-4052 1900);
PAINT MONO (-4052 1900);
FORCEPROP 2 LAST CDS_LIB standard
J 0
(-3800 1900);
PAINT MONO (-3800 1900);
DISPLAY INVISIBLE (-3800 1900);
FORCEPROP 1 LAST OFFPAGE TRUE
J 0
(-3475 1775);
DISPLAY 0.872340 (-3475 1775);
DISPLAY INVISIBLE (-3475 1775);
FORCEPROP 1 LAST COMMENT_BODY TRUE
J 0
(-3675 1800);
DISPLAY 0.872340 (-3675 1800);
PAINT GREEN (-3675 1800);
DISPLAY INVISIBLE (-3675 1800);
FORCEPROP 2 LAST PATH I10
J 0
(-3750 1975);
DISPLAY 1.021277 (-3750 1975);
DISPLAY INVISIBLE (-3750 1975);
FORCEADD TAP..1
(-1225 3300);
FORCEPROP 3 LASTPIN (-1275 3300) SIG_NAME M_C_CPU0_SA_DQ<14>
J 0
(-1265 3310);
DISPLAY 0.659574 (-1265 3310);
PAINT MONO (-1265 3310);
DISPLAY INVISIBLE (-1265 3310);
FORCEPROP 1 LASTPIN (-1275 3300) BN 14
J 0
(-1287 3308);
DISPLAY 0.680851 (-1287 3308);
PAINT GREEN (-1287 3308);
FORCEPROP 2 LAST CDS_LIB standard
J 0
(-1225 3300);
PAINT MONO (-1225 3300);
DISPLAY INVISIBLE (-1225 3300);
FORCEPROP 1 LAST BODY_TYPE PLUMBING
J 0
(-1225 3350);
DISPLAY 0.872340 (-1225 3350);
PAINT GREEN (-1225 3350);
DISPLAY INVISIBLE (-1225 3350);
FORCEPROP 1 LAST HDL_TAP TRUE
J 0
(-900 3175);
DISPLAY 0.872340 (-900 3175);
DISPLAY INVISIBLE (-900 3175);
FORCEPROP 1 LAST PATH I100
J 0
(-1227 3300);
DISPLAY 0.872340 (-1227 3300);
PAINT GREEN (-1227 3300);
DISPLAY INVISIBLE (-1227 3300);
FORCEADD TAP..1
(-1225 3200);
FORCEPROP 3 LASTPIN (-1275 3200) SIG_NAME M_C_CPU0_SA_DQ<12>
J 0
(-1265 3210);
DISPLAY 0.659574 (-1265 3210);
PAINT MONO (-1265 3210);
DISPLAY INVISIBLE (-1265 3210);
FORCEPROP 1 LASTPIN (-1275 3200) BN 12
J 0
(-1287 3208);
DISPLAY 0.680851 (-1287 3208);
PAINT GREEN (-1287 3208);
FORCEPROP 2 LAST CDS_LIB standard
J 0
(-1225 3200);
PAINT MONO (-1225 3200);
DISPLAY INVISIBLE (-1225 3200);
FORCEPROP 1 LAST BODY_TYPE PLUMBING
J 0
(-1225 3250);
DISPLAY 0.872340 (-1225 3250);
PAINT GREEN (-1225 3250);
DISPLAY INVISIBLE (-1225 3250);
FORCEPROP 1 LAST HDL_TAP TRUE
J 0
(-900 3075);
DISPLAY 0.872340 (-900 3075);
DISPLAY INVISIBLE (-900 3075);
FORCEPROP 1 LAST PATH I101
J 0
(-1227 3200);
DISPLAY 0.872340 (-1227 3200);
PAINT GREEN (-1227 3200);
DISPLAY INVISIBLE (-1227 3200);
FORCEADD TAP..1
(-1225 3350);
FORCEPROP 3 LASTPIN (-1275 3350) SIG_NAME M_C_CPU0_SA_DQ<15>
J 0
(-1265 3360);
DISPLAY 0.659574 (-1265 3360);
PAINT MONO (-1265 3360);
DISPLAY INVISIBLE (-1265 3360);
FORCEPROP 1 LASTPIN (-1275 3350) BN 15
J 0
(-1287 3358);
DISPLAY 0.680851 (-1287 3358);
PAINT GREEN (-1287 3358);
FORCEPROP 2 LAST CDS_LIB standard
J 0
(-1225 3350);
PAINT MONO (-1225 3350);
DISPLAY INVISIBLE (-1225 3350);
FORCEPROP 1 LAST BODY_TYPE PLUMBING
J 0
(-1225 3400);
DISPLAY 0.872340 (-1225 3400);
PAINT GREEN (-1225 3400);
DISPLAY INVISIBLE (-1225 3400);
FORCEPROP 1 LAST HDL_TAP TRUE
J 0
(-900 3225);
DISPLAY 0.872340 (-900 3225);
DISPLAY INVISIBLE (-900 3225);
FORCEPROP 1 LAST PATH I102
J 0
(-1227 3350);
DISPLAY 0.872340 (-1227 3350);
PAINT GREEN (-1227 3350);
DISPLAY INVISIBLE (-1227 3350);
FORCEADD TAP..1
(-1225 3400);
FORCEPROP 3 LASTPIN (-1275 3400) SIG_NAME M_C_CPU0_SA_DQ<16>
J 0
(-1265 3410);
DISPLAY 0.659574 (-1265 3410);
PAINT MONO (-1265 3410);
DISPLAY INVISIBLE (-1265 3410);
FORCEPROP 1 LASTPIN (-1275 3400) BN 16
J 0
(-1287 3408);
DISPLAY 0.680851 (-1287 3408);
PAINT GREEN (-1287 3408);
FORCEPROP 2 LAST CDS_LIB standard
J 0
(-1225 3400);
PAINT MONO (-1225 3400);
DISPLAY INVISIBLE (-1225 3400);
FORCEPROP 1 LAST BODY_TYPE PLUMBING
J 0
(-1225 3450);
DISPLAY 0.872340 (-1225 3450);
PAINT GREEN (-1225 3450);
DISPLAY INVISIBLE (-1225 3450);
FORCEPROP 1 LAST HDL_TAP TRUE
J 0
(-900 3275);
DISPLAY 0.872340 (-900 3275);
DISPLAY INVISIBLE (-900 3275);
FORCEPROP 1 LAST PATH I103
J 0
(-1227 3400);
DISPLAY 0.872340 (-1227 3400);
PAINT GREEN (-1227 3400);
DISPLAY INVISIBLE (-1227 3400);
FORCEADD TAP..1
(-1225 3550);
FORCEPROP 3 LASTPIN (-1275 3550) SIG_NAME M_C_CPU0_SA_DQ<19>
J 0
(-1265 3560);
DISPLAY 0.659574 (-1265 3560);
PAINT MONO (-1265 3560);
DISPLAY INVISIBLE (-1265 3560);
FORCEPROP 1 LASTPIN (-1275 3550) BN 19
J 0
(-1287 3558);
DISPLAY 0.680851 (-1287 3558);
PAINT GREEN (-1287 3558);
FORCEPROP 2 LAST CDS_LIB standard
J 0
(-1225 3550);
PAINT MONO (-1225 3550);
DISPLAY INVISIBLE (-1225 3550);
FORCEPROP 1 LAST BODY_TYPE PLUMBING
J 0
(-1225 3600);
DISPLAY 0.872340 (-1225 3600);
PAINT GREEN (-1225 3600);
DISPLAY INVISIBLE (-1225 3600);
FORCEPROP 1 LAST HDL_TAP TRUE
J 0
(-900 3425);
DISPLAY 0.872340 (-900 3425);
DISPLAY INVISIBLE (-900 3425);
FORCEPROP 1 LAST PATH I104
J 0
(-1227 3550);
DISPLAY 0.872340 (-1227 3550);
PAINT GREEN (-1227 3550);
DISPLAY INVISIBLE (-1227 3550);
FORCEADD TAP..1
(-1225 3500);
FORCEPROP 3 LASTPIN (-1275 3500) SIG_NAME M_C_CPU0_SA_DQ<18>
J 0
(-1265 3510);
DISPLAY 0.659574 (-1265 3510);
PAINT MONO (-1265 3510);
DISPLAY INVISIBLE (-1265 3510);
FORCEPROP 1 LASTPIN (-1275 3500) BN 18
J 0
(-1287 3508);
DISPLAY 0.680851 (-1287 3508);
PAINT GREEN (-1287 3508);
FORCEPROP 2 LAST CDS_LIB standard
J 0
(-1225 3500);
PAINT MONO (-1225 3500);
DISPLAY INVISIBLE (-1225 3500);
FORCEPROP 1 LAST BODY_TYPE PLUMBING
J 0
(-1225 3550);
DISPLAY 0.872340 (-1225 3550);
PAINT GREEN (-1225 3550);
DISPLAY INVISIBLE (-1225 3550);
FORCEPROP 1 LAST HDL_TAP TRUE
J 0
(-900 3375);
DISPLAY 0.872340 (-900 3375);
DISPLAY INVISIBLE (-900 3375);
FORCEPROP 1 LAST PATH I105
J 0
(-1227 3500);
DISPLAY 0.872340 (-1227 3500);
PAINT GREEN (-1227 3500);
DISPLAY INVISIBLE (-1227 3500);
FORCEADD TAP..1
(-1225 3450);
FORCEPROP 3 LASTPIN (-1275 3450) SIG_NAME M_C_CPU0_SA_DQ<17>
J 0
(-1265 3460);
DISPLAY 0.659574 (-1265 3460);
PAINT MONO (-1265 3460);
DISPLAY INVISIBLE (-1265 3460);
FORCEPROP 1 LASTPIN (-1275 3450) BN 17
J 0
(-1287 3458);
DISPLAY 0.680851 (-1287 3458);
PAINT GREEN (-1287 3458);
FORCEPROP 2 LAST CDS_LIB standard
J 0
(-1225 3450);
PAINT MONO (-1225 3450);
DISPLAY INVISIBLE (-1225 3450);
FORCEPROP 1 LAST BODY_TYPE PLUMBING
J 0
(-1225 3500);
DISPLAY 0.872340 (-1225 3500);
PAINT GREEN (-1225 3500);
DISPLAY INVISIBLE (-1225 3500);
FORCEPROP 1 LAST HDL_TAP TRUE
J 0
(-900 3325);
DISPLAY 0.872340 (-900 3325);
DISPLAY INVISIBLE (-900 3325);
FORCEPROP 1 LAST PATH I106
J 0
(-1227 3450);
DISPLAY 0.872340 (-1227 3450);
PAINT GREEN (-1227 3450);
DISPLAY INVISIBLE (-1227 3450);
FORCEADD TAP..1
(-1225 3650);
FORCEPROP 3 LASTPIN (-1275 3650) SIG_NAME M_C_CPU0_SA_DQ<21>
J 0
(-1265 3660);
DISPLAY 0.659574 (-1265 3660);
PAINT MONO (-1265 3660);
DISPLAY INVISIBLE (-1265 3660);
FORCEPROP 1 LASTPIN (-1275 3650) BN 21
J 0
(-1287 3658);
DISPLAY 0.680851 (-1287 3658);
PAINT GREEN (-1287 3658);
FORCEPROP 2 LAST CDS_LIB standard
J 0
(-1225 3650);
PAINT MONO (-1225 3650);
DISPLAY INVISIBLE (-1225 3650);
FORCEPROP 1 LAST BODY_TYPE PLUMBING
J 0
(-1225 3700);
DISPLAY 0.872340 (-1225 3700);
PAINT GREEN (-1225 3700);
DISPLAY INVISIBLE (-1225 3700);
FORCEPROP 1 LAST HDL_TAP TRUE
J 0
(-900 3525);
DISPLAY 0.872340 (-900 3525);
DISPLAY INVISIBLE (-900 3525);
FORCEPROP 1 LAST PATH I107
J 0
(-1227 3650);
DISPLAY 0.872340 (-1227 3650);
PAINT GREEN (-1227 3650);
DISPLAY INVISIBLE (-1227 3650);
FORCEADD TAP..1
(-1225 3600);
FORCEPROP 3 LASTPIN (-1275 3600) SIG_NAME M_C_CPU0_SA_DQ<20>
J 0
(-1265 3610);
DISPLAY 0.659574 (-1265 3610);
PAINT MONO (-1265 3610);
DISPLAY INVISIBLE (-1265 3610);
FORCEPROP 1 LASTPIN (-1275 3600) BN 20
J 0
(-1287 3608);
DISPLAY 0.680851 (-1287 3608);
PAINT GREEN (-1287 3608);
FORCEPROP 2 LAST CDS_LIB standard
J 0
(-1225 3600);
PAINT MONO (-1225 3600);
DISPLAY INVISIBLE (-1225 3600);
FORCEPROP 1 LAST BODY_TYPE PLUMBING
J 0
(-1225 3650);
DISPLAY 0.872340 (-1225 3650);
PAINT GREEN (-1225 3650);
DISPLAY INVISIBLE (-1225 3650);
FORCEPROP 1 LAST HDL_TAP TRUE
J 0
(-900 3475);
DISPLAY 0.872340 (-900 3475);
DISPLAY INVISIBLE (-900 3475);
FORCEPROP 1 LAST PATH I108
J 0
(-1227 3600);
DISPLAY 0.872340 (-1227 3600);
PAINT GREEN (-1227 3600);
DISPLAY INVISIBLE (-1227 3600);
FORCEADD TAP..1
(-1225 3700);
FORCEPROP 3 LASTPIN (-1275 3700) SIG_NAME M_C_CPU0_SA_DQ<22>
J 0
(-1265 3710);
DISPLAY 0.659574 (-1265 3710);
PAINT MONO (-1265 3710);
DISPLAY INVISIBLE (-1265 3710);
FORCEPROP 1 LASTPIN (-1275 3700) BN 22
J 0
(-1287 3708);
DISPLAY 0.680851 (-1287 3708);
PAINT GREEN (-1287 3708);
FORCEPROP 2 LAST CDS_LIB standard
J 0
(-1225 3700);
DISPLAY INVISIBLE (-1225 3700);
FORCEPROP 1 LAST BODY_TYPE PLUMBING
J 0
(-1225 3750);
DISPLAY 0.872340 (-1225 3750);
PAINT GREEN (-1225 3750);
DISPLAY INVISIBLE (-1225 3750);
FORCEPROP 1 LAST HDL_TAP TRUE
J 0
(-900 3575);
DISPLAY 0.872340 (-900 3575);
DISPLAY INVISIBLE (-900 3575);
FORCEPROP 1 LAST PATH I109
J 0
(-1227 3700);
DISPLAY 0.872340 (-1227 3700);
PAINT GREEN (-1227 3700);
DISPLAY INVISIBLE (-1227 3700);
FORCEADD OFFPAGE..3
R 2
(-3800 2325);
FORCEPROP 2 LAST $XR1 87 
J 0
(-4139 2325);
DISPLAY 0.638298 (-4139 2325);
PAINT MONO (-4139 2325);
FORCEPROP 2 LAST $XR0 22 
J 0
(-4049 2325);
DISPLAY 0.638298 (-4049 2325);
PAINT MONO (-4049 2325);
FORCEPROP 2 LAST CDS_LIB standard
J 0
(-3800 2325);
PAINT MONO (-3800 2325);
DISPLAY INVISIBLE (-3800 2325);
FORCEPROP 1 LAST OFFPAGE TRUE
J 2
(-4125 2200);
DISPLAY 0.872340 (-4125 2200);
DISPLAY INVISIBLE (-4125 2200);
FORCEPROP 1 LAST COMMENT_BODY TRUE
J 2
(-3750 2225);
DISPLAY 0.872340 (-3750 2225);
PAINT GREEN (-3750 2225);
DISPLAY INVISIBLE (-3750 2225);
FORCEPROP 2 LAST PATH I11
J 0
(-3750 2400);
DISPLAY 1.021277 (-3750 2400);
DISPLAY INVISIBLE (-3750 2400);
FORCEADD TAP..1
(-1225 3750);
FORCEPROP 3 LASTPIN (-1275 3750) SIG_NAME M_C_CPU0_SA_DQ<23>
J 0
(-1265 3760);
DISPLAY 0.659574 (-1265 3760);
PAINT MONO (-1265 3760);
DISPLAY INVISIBLE (-1265 3760);
FORCEPROP 1 LASTPIN (-1275 3750) BN 23
J 0
(-1287 3758);
DISPLAY 0.680851 (-1287 3758);
PAINT GREEN (-1287 3758);
FORCEPROP 2 LAST CDS_LIB standard
J 0
(-1225 3750);
DISPLAY INVISIBLE (-1225 3750);
FORCEPROP 1 LAST BODY_TYPE PLUMBING
J 0
(-1225 3800);
DISPLAY 0.872340 (-1225 3800);
PAINT GREEN (-1225 3800);
DISPLAY INVISIBLE (-1225 3800);
FORCEPROP 1 LAST HDL_TAP TRUE
J 0
(-900 3625);
DISPLAY 0.872340 (-900 3625);
DISPLAY INVISIBLE (-900 3625);
FORCEPROP 1 LAST PATH I110
J 0
(-1227 3750);
DISPLAY 0.872340 (-1227 3750);
PAINT GREEN (-1227 3750);
DISPLAY INVISIBLE (-1227 3750);
FORCEADD TAP..1
(-1225 3800);
FORCEPROP 3 LASTPIN (-1275 3800) SIG_NAME M_C_CPU0_SA_DQ<24>
J 0
(-1265 3810);
DISPLAY 0.659574 (-1265 3810);
PAINT MONO (-1265 3810);
DISPLAY INVISIBLE (-1265 3810);
FORCEPROP 1 LASTPIN (-1275 3800) BN 24
J 0
(-1287 3808);
DISPLAY 0.680851 (-1287 3808);
PAINT GREEN (-1287 3808);
FORCEPROP 2 LAST CDS_LIB standard
J 0
(-1225 3800);
DISPLAY INVISIBLE (-1225 3800);
FORCEPROP 1 LAST BODY_TYPE PLUMBING
J 0
(-1225 3850);
DISPLAY 0.872340 (-1225 3850);
PAINT GREEN (-1225 3850);
DISPLAY INVISIBLE (-1225 3850);
FORCEPROP 1 LAST HDL_TAP TRUE
J 0
(-900 3675);
DISPLAY 0.872340 (-900 3675);
DISPLAY INVISIBLE (-900 3675);
FORCEPROP 1 LAST PATH I111
J 0
(-1227 3800);
DISPLAY 0.872340 (-1227 3800);
PAINT GREEN (-1227 3800);
DISPLAY INVISIBLE (-1227 3800);
FORCEADD TAP..1
(-1225 3850);
FORCEPROP 3 LASTPIN (-1275 3850) SIG_NAME M_C_CPU0_SA_DQ<25>
J 0
(-1265 3860);
DISPLAY 0.659574 (-1265 3860);
PAINT MONO (-1265 3860);
DISPLAY INVISIBLE (-1265 3860);
FORCEPROP 1 LASTPIN (-1275 3850) BN 25
J 0
(-1287 3858);
DISPLAY 0.680851 (-1287 3858);
PAINT GREEN (-1287 3858);
FORCEPROP 2 LAST CDS_LIB standard
J 0
(-1225 3850);
DISPLAY INVISIBLE (-1225 3850);
FORCEPROP 1 LAST BODY_TYPE PLUMBING
J 0
(-1225 3900);
DISPLAY 0.872340 (-1225 3900);
PAINT GREEN (-1225 3900);
DISPLAY INVISIBLE (-1225 3900);
FORCEPROP 1 LAST HDL_TAP TRUE
J 0
(-900 3725);
DISPLAY 0.872340 (-900 3725);
DISPLAY INVISIBLE (-900 3725);
FORCEPROP 1 LAST PATH I112
J 0
(-1227 3850);
DISPLAY 0.872340 (-1227 3850);
PAINT GREEN (-1227 3850);
DISPLAY INVISIBLE (-1227 3850);
FORCEADD TAP..1
(-1225 3900);
FORCEPROP 3 LASTPIN (-1275 3900) SIG_NAME M_C_CPU0_SA_DQ<26>
J 0
(-1265 3910);
DISPLAY 0.659574 (-1265 3910);
PAINT MONO (-1265 3910);
DISPLAY INVISIBLE (-1265 3910);
FORCEPROP 1 LASTPIN (-1275 3900) BN 26
J 0
(-1287 3908);
DISPLAY 0.680851 (-1287 3908);
PAINT GREEN (-1287 3908);
FORCEPROP 2 LAST CDS_LIB standard
J 0
(-1225 3900);
DISPLAY INVISIBLE (-1225 3900);
FORCEPROP 1 LAST BODY_TYPE PLUMBING
J 0
(-1225 3950);
DISPLAY 0.872340 (-1225 3950);
PAINT GREEN (-1225 3950);
DISPLAY INVISIBLE (-1225 3950);
FORCEPROP 1 LAST HDL_TAP TRUE
J 0
(-900 3775);
DISPLAY 0.872340 (-900 3775);
DISPLAY INVISIBLE (-900 3775);
FORCEPROP 1 LAST PATH I113
J 0
(-1227 3900);
DISPLAY 0.872340 (-1227 3900);
PAINT GREEN (-1227 3900);
DISPLAY INVISIBLE (-1227 3900);
FORCEADD TAP..1
(-1225 4050);
FORCEPROP 3 LASTPIN (-1275 4050) SIG_NAME M_C_CPU0_SA_DQ<29>
J 0
(-1265 4060);
DISPLAY 0.659574 (-1265 4060);
PAINT MONO (-1265 4060);
DISPLAY INVISIBLE (-1265 4060);
FORCEPROP 1 LASTPIN (-1275 4050) BN 29
J 0
(-1287 4058);
DISPLAY 0.680851 (-1287 4058);
PAINT GREEN (-1287 4058);
FORCEPROP 2 LAST CDS_LIB standard
J 0
(-1225 4050);
DISPLAY INVISIBLE (-1225 4050);
FORCEPROP 1 LAST BODY_TYPE PLUMBING
J 0
(-1225 4100);
DISPLAY 0.872340 (-1225 4100);
PAINT GREEN (-1225 4100);
DISPLAY INVISIBLE (-1225 4100);
FORCEPROP 1 LAST HDL_TAP TRUE
J 0
(-900 3925);
DISPLAY 0.872340 (-900 3925);
DISPLAY INVISIBLE (-900 3925);
FORCEPROP 1 LAST PATH I114
J 0
(-1227 4050);
DISPLAY 0.872340 (-1227 4050);
PAINT GREEN (-1227 4050);
DISPLAY INVISIBLE (-1227 4050);
FORCEADD TAP..1
(-1225 3950);
FORCEPROP 3 LASTPIN (-1275 3950) SIG_NAME M_C_CPU0_SA_DQ<27>
J 0
(-1265 3960);
DISPLAY 0.659574 (-1265 3960);
PAINT MONO (-1265 3960);
DISPLAY INVISIBLE (-1265 3960);
FORCEPROP 1 LASTPIN (-1275 3950) BN 27
J 0
(-1287 3958);
DISPLAY 0.680851 (-1287 3958);
PAINT GREEN (-1287 3958);
FORCEPROP 2 LAST CDS_LIB standard
J 0
(-1225 3950);
DISPLAY INVISIBLE (-1225 3950);
FORCEPROP 1 LAST BODY_TYPE PLUMBING
J 0
(-1225 4000);
DISPLAY 0.872340 (-1225 4000);
PAINT GREEN (-1225 4000);
DISPLAY INVISIBLE (-1225 4000);
FORCEPROP 1 LAST HDL_TAP TRUE
J 0
(-900 3825);
DISPLAY 0.872340 (-900 3825);
DISPLAY INVISIBLE (-900 3825);
FORCEPROP 1 LAST PATH I115
J 0
(-1227 3950);
DISPLAY 0.872340 (-1227 3950);
PAINT GREEN (-1227 3950);
DISPLAY INVISIBLE (-1227 3950);
FORCEADD TAP..1
(-1225 4000);
FORCEPROP 3 LASTPIN (-1275 4000) SIG_NAME M_C_CPU0_SA_DQ<28>
J 0
(-1265 4010);
DISPLAY 0.659574 (-1265 4010);
PAINT MONO (-1265 4010);
DISPLAY INVISIBLE (-1265 4010);
FORCEPROP 1 LASTPIN (-1275 4000) BN 28
J 0
(-1287 4008);
DISPLAY 0.680851 (-1287 4008);
PAINT GREEN (-1287 4008);
FORCEPROP 2 LAST CDS_LIB standard
J 0
(-1225 4000);
DISPLAY INVISIBLE (-1225 4000);
FORCEPROP 1 LAST BODY_TYPE PLUMBING
J 0
(-1225 4050);
DISPLAY 0.872340 (-1225 4050);
PAINT GREEN (-1225 4050);
DISPLAY INVISIBLE (-1225 4050);
FORCEPROP 1 LAST HDL_TAP TRUE
J 0
(-900 3875);
DISPLAY 0.872340 (-900 3875);
DISPLAY INVISIBLE (-900 3875);
FORCEPROP 1 LAST PATH I116
J 0
(-1227 4000);
DISPLAY 0.872340 (-1227 4000);
PAINT GREEN (-1227 4000);
DISPLAY INVISIBLE (-1227 4000);
FORCEADD TAP..1
(-1225 4150);
FORCEPROP 3 LASTPIN (-1275 4150) SIG_NAME M_C_CPU0_SA_DQ<31>
J 0
(-1265 4160);
DISPLAY 0.659574 (-1265 4160);
PAINT MONO (-1265 4160);
DISPLAY INVISIBLE (-1265 4160);
FORCEPROP 1 LASTPIN (-1275 4150) BN 31
J 0
(-1287 4158);
DISPLAY 0.680851 (-1287 4158);
PAINT GREEN (-1287 4158);
FORCEPROP 2 LAST CDS_LIB standard
J 0
(-1225 4150);
DISPLAY INVISIBLE (-1225 4150);
FORCEPROP 1 LAST BODY_TYPE PLUMBING
J 0
(-1225 4200);
DISPLAY 0.872340 (-1225 4200);
PAINT GREEN (-1225 4200);
DISPLAY INVISIBLE (-1225 4200);
FORCEPROP 1 LAST HDL_TAP TRUE
J 0
(-900 4025);
DISPLAY 0.872340 (-900 4025);
DISPLAY INVISIBLE (-900 4025);
FORCEPROP 1 LAST PATH I117
J 0
(-1227 4150);
DISPLAY 0.872340 (-1227 4150);
PAINT GREEN (-1227 4150);
DISPLAY INVISIBLE (-1227 4150);
FORCEADD TAP..1
(-1225 4100);
FORCEPROP 3 LASTPIN (-1275 4100) SIG_NAME M_C_CPU0_SA_DQ<30>
J 0
(-1265 4110);
DISPLAY 0.659574 (-1265 4110);
PAINT MONO (-1265 4110);
DISPLAY INVISIBLE (-1265 4110);
FORCEPROP 1 LASTPIN (-1275 4100) BN 30
J 0
(-1287 4108);
DISPLAY 0.680851 (-1287 4108);
PAINT GREEN (-1287 4108);
FORCEPROP 2 LAST CDS_LIB standard
J 0
(-1225 4100);
DISPLAY INVISIBLE (-1225 4100);
FORCEPROP 1 LAST BODY_TYPE PLUMBING
J 0
(-1225 4150);
DISPLAY 0.872340 (-1225 4150);
PAINT GREEN (-1225 4150);
DISPLAY INVISIBLE (-1225 4150);
FORCEPROP 1 LAST HDL_TAP TRUE
J 0
(-900 3975);
DISPLAY 0.872340 (-900 3975);
DISPLAY INVISIBLE (-900 3975);
FORCEPROP 1 LAST PATH I118
J 0
(-1227 4100);
DISPLAY 0.872340 (-1227 4100);
PAINT GREEN (-1227 4100);
DISPLAY INVISIBLE (-1227 4100);
FORCEADD UNIVERSAL_GND..1
(500 -100);
FORCEPROP 3 LASTPIN (500 -50) SIG_NAME GND\g
J 0
(510 -40);
DISPLAY 0.659574 (510 -40);
PAINT MONO (510 -40);
DISPLAY INVISIBLE (510 -40);
FORCEPROP 2 LAST CDS_LIB logical_power
J 0
(500 -100);
PAINT MONO (500 -100);
DISPLAY INVISIBLE (500 -100);
FORCEPROP 1 LAST HDL_POWER GND
J 1
(525 -175);
DISPLAY 0.872340 (525 -175);
PAINT GREEN (525 -175);
DISPLAY INVISIBLE (525 -175);
FORCEPROP 1 LAST PATH I119
J 0
(575 -100);
DISPLAY 0.872340 (575 -100);
PAINT AQUA (575 -100);
DISPLAY INVISIBLE (575 -100);
FORCEADD VCC_CORE..1
(-3700 2025);
FORCEPROP 3 LASTPIN (-3700 1975) SIG_NAME P3V3_AUX\g
J 0
(-3690 1985);
DISPLAY 0.659574 (-3690 1985);
PAINT MONO (-3690 1985);
DISPLAY INVISIBLE (-3690 1985);
FORCEPROP 1 LAST HDL_POWER P3V3_AUX
J 1
(-3700 2075);
DISPLAY 1.148936 (-3700 2075);
PAINT GREEN (-3700 2075);
FORCEPROP 2 LAST CDS_LIB logical_power
J 0
(-3700 2025);
PAINT MONO (-3700 2025);
DISPLAY INVISIBLE (-3700 2025);
FORCEPROP 1 LAST PATH I12
J 0
(-3650 2050);
DISPLAY 0.872340 (-3650 2050);
PAINT AQUA (-3650 2050);
DISPLAY INVISIBLE (-3650 2050);
FORCEADD Q_CAP..1
(500 275);
FORCEPROP 1 LAST PART_NUMBER CH5221MEB00
J 0
(550 125);
DISPLAY 0.978723 (550 125);
DISPLAY INVISIBLE (550 125);
FORCEPROP 1 LAST PACK_TYPE C0402
J 0
(550 75);
DISPLAY 0.978723 (550 75);
FORCEPROP 1 LAST TOLERANCE 20%
J 0
(550 225);
DISPLAY 0.978723 (550 225);
FORCEPROP 1 LAST VALUE 2.2UF
J 0
(550 325);
DISPLAY 0.978723 (550 325);
FORCEPROP 1 LAST MATERIAL X6S
J 0
(550 175);
DISPLAY 0.978723 (550 175);
FORCEPROP 1 LAST VOLTAGE 6.3V
J 0
(550 275);
DISPLAY 0.978723 (550 275);
FORCEPROP 1 LAST $LOCATION C14
J 0
(550 375);
DISPLAY 0.978723 (550 375);
FORCEPROP 1 LASTPIN (500 375) $PN 1
J 0
(510 355);
DISPLAY 0.787234 (510 355);
FORCEPROP 1 LASTPIN (500 175) $PN 2
J 0
(510 155);
DISPLAY 0.787234 (510 155);
FORCEPROP 2 LAST CDS_LIB pure_quanta
J 0
(500 275);
PAINT MONO (500 275);
DISPLAY INVISIBLE (500 275);
FORCEPROP 2 LAST CDS_LOCATION C14
J 0
(550 475);
DISPLAY 1.021277 (550 475);
DISPLAY INVISIBLE (550 475);
FORCEPROP 2 LAST $SEC 1
J 0
(550 475);
DISPLAY 0.680851 (550 475);
PAINT MONO (550 475);
DISPLAY INVISIBLE (550 475);
FORCEPROP 2 LAST CDS_SEC 1
J 0
(550 475);
DISPLAY 1.021277 (550 475);
DISPLAY INVISIBLE (550 475);
FORCEPROP 1 LAST PATH I120
J 0
(550 425);
DISPLAY 0.978723 (550 425);
PAINT WHITE (550 425);
DISPLAY INVISIBLE (550 425);
FORCEADD Q_CAP..1
(1500 275);
FORCEPROP 1 LAST PART_NUMBER CH6103KEA00
J 0
(1550 125);
DISPLAY 0.978723 (1550 125);
DISPLAY INVISIBLE (1550 125);
FORCEPROP 1 LAST VOLTAGE 16V
J 0
(1550 275);
DISPLAY 0.978723 (1550 275);
FORCEPROP 1 LAST VALUE 10UF
J 0
(1550 325);
DISPLAY 0.978723 (1550 325);
FORCEPROP 1 LAST TOLERANCE 10%
J 0
(1550 225);
DISPLAY 0.978723 (1550 225);
FORCEPROP 1 LAST MATERIAL X6S
J 0
(1550 175);
DISPLAY 0.978723 (1550 175);
FORCEPROP 1 LAST PACK_TYPE C0805
J 0
(1550 75);
DISPLAY 0.978723 (1550 75);
FORCEPROP 1 LAST $LOCATION C15
J 0
(1550 375);
DISPLAY 0.978723 (1550 375);
FORCEPROP 1 LASTPIN (1500 375) $PN 1
J 0
(1510 355);
DISPLAY 0.787234 (1510 355);
FORCEPROP 1 LASTPIN (1500 175) $PN 2
J 0
(1510 155);
DISPLAY 0.787234 (1510 155);
FORCEPROP 2 LAST CDS_LIB pure_quanta
J 0
(1500 275);
PAINT MONO (1500 275);
DISPLAY INVISIBLE (1500 275);
FORCEPROP 2 LAST CDS_LOCATION C15
J 0
(1550 475);
DISPLAY 1.021277 (1550 475);
DISPLAY INVISIBLE (1550 475);
FORCEPROP 2 LAST $SEC 1
J 0
(1550 475);
DISPLAY 0.680851 (1550 475);
PAINT MONO (1550 475);
DISPLAY INVISIBLE (1550 475);
FORCEPROP 2 LAST CDS_SEC 1
J 0
(1550 475);
DISPLAY 1.021277 (1550 475);
DISPLAY INVISIBLE (1550 475);
FORCEPROP 1 LAST PATH I121
J 0
(1550 425);
DISPLAY 0.978723 (1550 425);
PAINT WHITE (1550 425);
DISPLAY INVISIBLE (1550 425);
FORCEADD UNIVERSAL_GND..1
(2125 -100);
FORCEPROP 3 LASTPIN (2125 -50) SIG_NAME GND\g
J 0
(2135 -40);
DISPLAY 0.659574 (2135 -40);
PAINT MONO (2135 -40);
DISPLAY INVISIBLE (2135 -40);
FORCEPROP 2 LAST CDS_LIB logical_power
J 0
(2125 -100);
PAINT MONO (2125 -100);
DISPLAY INVISIBLE (2125 -100);
FORCEPROP 1 LAST HDL_POWER GND
J 1
(2150 -175);
DISPLAY 0.872340 (2150 -175);
PAINT GREEN (2150 -175);
DISPLAY INVISIBLE (2150 -175);
FORCEPROP 1 LAST PATH I122
J 0
(2200 -100);
DISPLAY 0.872340 (2200 -100);
PAINT AQUA (2200 -100);
DISPLAY INVISIBLE (2200 -100);
FORCEADD Q_CAP..1
(2125 275);
FORCEPROP 1 LAST PART_NUMBER CH6103KEA00
J 0
(2175 125);
DISPLAY 0.978723 (2175 125);
DISPLAY INVISIBLE (2175 125);
FORCEPROP 1 LAST TOLERANCE 10%
J 0
(2175 225);
DISPLAY 0.978723 (2175 225);
FORCEPROP 1 LAST VALUE 10UF
J 0
(2175 325);
DISPLAY 0.978723 (2175 325);
FORCEPROP 1 LAST VOLTAGE 16V
J 0
(2175 275);
DISPLAY 0.978723 (2175 275);
FORCEPROP 1 LAST MATERIAL X6S
J 0
(2175 175);
DISPLAY 0.978723 (2175 175);
FORCEPROP 1 LAST PACK_TYPE C0805
J 0
(2175 75);
DISPLAY 0.978723 (2175 75);
FORCEPROP 1 LAST $LOCATION C16
J 0
(2175 375);
DISPLAY 0.978723 (2175 375);
FORCEPROP 1 LASTPIN (2125 375) $PN 1
J 0
(2135 355);
DISPLAY 0.787234 (2135 355);
FORCEPROP 1 LASTPIN (2125 175) $PN 2
J 0
(2135 155);
DISPLAY 0.787234 (2135 155);
FORCEPROP 2 LAST CDS_LIB pure_quanta
J 0
(2125 275);
PAINT MONO (2125 275);
DISPLAY INVISIBLE (2125 275);
FORCEPROP 2 LAST CDS_LOCATION C16
J 0
(2175 475);
DISPLAY 1.021277 (2175 475);
DISPLAY INVISIBLE (2175 475);
FORCEPROP 2 LAST $SEC 1
J 0
(2175 475);
DISPLAY 0.680851 (2175 475);
PAINT MONO (2175 475);
DISPLAY INVISIBLE (2175 475);
FORCEPROP 2 LAST CDS_SEC 1
J 0
(2175 475);
DISPLAY 1.021277 (2175 475);
DISPLAY INVISIBLE (2175 475);
FORCEPROP 1 LAST PATH I123
J 0
(2175 425);
DISPLAY 0.978723 (2175 425);
PAINT WHITE (2175 425);
DISPLAY INVISIBLE (2175 425);
FORCEADD VCC_CORE..1
(500 600);
FORCEPROP 3 LASTPIN (500 550) SIG_NAME P3V3_AUX\g
J 0
(510 560);
DISPLAY 0.659574 (510 560);
PAINT MONO (510 560);
DISPLAY INVISIBLE (510 560);
FORCEPROP 1 LAST HDL_POWER P3V3_AUX
J 1
(500 650);
DISPLAY 1.148936 (500 650);
PAINT GREEN (500 650);
FORCEPROP 2 LAST CDS_LIB logical_power
J 0
(500 600);
PAINT MONO (500 600);
DISPLAY INVISIBLE (500 600);
FORCEPROP 1 LAST PATH I124
J 0
(550 625);
DISPLAY 0.872340 (550 625);
PAINT AQUA (550 625);
DISPLAY INVISIBLE (550 625);
FORCEADD OFFPAGE..3
(-400 2525);
FORCEPROP 2 LAST $XR1 87 
J 0
(-96 2525);
DISPLAY 0.638298 (-96 2525);
PAINT MONO (-96 2525);
FORCEPROP 2 LAST $XR0 22 
J 0
(-186 2525);
DISPLAY 0.638298 (-186 2525);
PAINT MONO (-186 2525);
FORCEPROP 2 LAST CDS_LIB standard
J 2
(-400 2525);
DISPLAY INVISIBLE (-400 2525);
FORCEPROP 1 LAST OFFPAGE TRUE
J 0
(-75 2400);
DISPLAY 0.872340 (-75 2400);
DISPLAY INVISIBLE (-75 2400);
FORCEPROP 1 LAST COMMENT_BODY TRUE
J 0
(-450 2425);
DISPLAY 0.872340 (-450 2425);
PAINT GREEN (-450 2425);
DISPLAY INVISIBLE (-450 2425);
FORCEPROP 2 LAST PATH I126
J 0
(-200 2600);
DISPLAY 1.021277 (-200 2600);
DISPLAY INVISIBLE (-200 2600);
FORCEADD OFFPAGE..3
(-400 4175);
FORCEPROP 2 LAST $XR1 87 
J 0
(-96 4175);
DISPLAY 0.638298 (-96 4175);
PAINT MONO (-96 4175);
FORCEPROP 2 LAST $XR0 22 
J 0
(-186 4175);
DISPLAY 0.638298 (-186 4175);
PAINT MONO (-186 4175);
FORCEPROP 2 LAST CDS_LIB standard
J 2
(-400 4175);
DISPLAY INVISIBLE (-400 4175);
FORCEPROP 1 LAST OFFPAGE TRUE
J 0
(-75 4050);
DISPLAY 0.872340 (-75 4050);
DISPLAY INVISIBLE (-75 4050);
FORCEPROP 1 LAST COMMENT_BODY TRUE
J 0
(-450 4075);
DISPLAY 0.872340 (-450 4075);
PAINT GREEN (-450 4075);
DISPLAY INVISIBLE (-450 4075);
FORCEPROP 2 LAST PATH I127
J 0
(-200 4250);
DISPLAY 1.021277 (-200 4250);
DISPLAY INVISIBLE (-200 4250);
FORCEADD VCC_CORE..1
(1500 600);
FORCEPROP 3 LASTPIN (1500 550) SIG_NAME P12V_S3_AUX_CPU0_NVDIMM\g
J 0
(1510 560);
DISPLAY 0.659574 (1510 560);
PAINT MONO (1510 560);
DISPLAY INVISIBLE (1510 560);
FORCEPROP 1 LAST HDL_POWER P12V_S3_AUX_CPU0_NVDIMM
J 1
(1500 650);
DISPLAY 1.148936 (1500 650);
PAINT GREEN (1500 650);
FORCEPROP 2 LAST CDS_LIB logical_power
J 0
(1500 600);
PAINT MONO (1500 600);
DISPLAY INVISIBLE (1500 600);
FORCEPROP 1 LAST PATH I128
J 0
(1550 625);
DISPLAY 0.872340 (1550 625);
PAINT AQUA (1550 625);
DISPLAY INVISIBLE (1550 625);
FORCEADD TAP..1
(1525 2200);
FORCEPROP 3 LASTPIN (1475 2200) SIG_NAME M_C_CPU0_SB_DQS_DP<0>
J 0
(1485 2210);
DISPLAY 0.659574 (1485 2210);
PAINT MONO (1485 2210);
DISPLAY INVISIBLE (1485 2210);
FORCEPROP 1 LASTPIN (1475 2200) BN 0
J 0
(1463 2208);
DISPLAY 0.680851 (1463 2208);
PAINT GREEN (1463 2208);
FORCEPROP 2 LAST CDS_LIB standard
J 0
(1525 2200);
PAINT MONO (1525 2200);
DISPLAY INVISIBLE (1525 2200);
FORCEPROP 1 LAST BODY_TYPE PLUMBING
J 0
(1525 2250);
DISPLAY 0.872340 (1525 2250);
PAINT GREEN (1525 2250);
DISPLAY INVISIBLE (1525 2250);
FORCEPROP 1 LAST HDL_TAP TRUE
J 0
(1850 2075);
DISPLAY 0.872340 (1850 2075);
DISPLAY INVISIBLE (1850 2075);
FORCEPROP 1 LAST PATH I129
J 0
(1523 2200);
DISPLAY 0.872340 (1523 2200);
PAINT GREEN (1523 2200);
DISPLAY INVISIBLE (1523 2200);
FORCEADD OFFPAGE..3
R 2
(-3800 2775);
FORCEPROP 2 LAST $XR1 87 
J 0
(-4139 2775);
DISPLAY 0.638298 (-4139 2775);
PAINT MONO (-4139 2775);
FORCEPROP 2 LAST $XR0 22 
J 0
(-4049 2775);
DISPLAY 0.638298 (-4049 2775);
PAINT MONO (-4049 2775);
FORCEPROP 2 LAST CDS_LIB standard
J 0
(-3800 2775);
PAINT MONO (-3800 2775);
DISPLAY INVISIBLE (-3800 2775);
FORCEPROP 1 LAST OFFPAGE TRUE
J 2
(-4125 2650);
DISPLAY 0.872340 (-4125 2650);
DISPLAY INVISIBLE (-4125 2650);
FORCEPROP 1 LAST COMMENT_BODY TRUE
J 2
(-3750 2675);
DISPLAY 0.872340 (-3750 2675);
PAINT GREEN (-3750 2675);
DISPLAY INVISIBLE (-3750 2675);
FORCEPROP 2 LAST PATH I13
J 0
(-3750 2850);
DISPLAY 1.021277 (-3750 2850);
DISPLAY INVISIBLE (-3750 2850);
FORCEADD TAP..1
(1700 2150);
FORCEPROP 3 LASTPIN (1650 2150) SIG_NAME M_C_CPU0_SB_DQS_DN<0>
J 0
(1660 2160);
DISPLAY 0.659574 (1660 2160);
PAINT MONO (1660 2160);
DISPLAY INVISIBLE (1660 2160);
FORCEPROP 1 LASTPIN (1650 2150) BN 0
J 0
(1638 2158);
DISPLAY 0.680851 (1638 2158);
PAINT GREEN (1638 2158);
FORCEPROP 2 LAST CDS_LIB standard
J 0
(1700 2150);
PAINT MONO (1700 2150);
DISPLAY INVISIBLE (1700 2150);
FORCEPROP 1 LAST BODY_TYPE PLUMBING
J 0
(1700 2200);
DISPLAY 0.872340 (1700 2200);
PAINT GREEN (1700 2200);
DISPLAY INVISIBLE (1700 2200);
FORCEPROP 1 LAST HDL_TAP TRUE
J 0
(2025 2025);
DISPLAY 0.872340 (2025 2025);
DISPLAY INVISIBLE (2025 2025);
FORCEPROP 1 LAST PATH I130
J 0
(1698 2150);
DISPLAY 0.872340 (1698 2150);
PAINT GREEN (1698 2150);
DISPLAY INVISIBLE (1698 2150);
FORCEADD TAP..1
(1700 2250);
FORCEPROP 3 LASTPIN (1650 2250) SIG_NAME M_C_CPU0_SB_DQS_DN<1>
J 0
(1660 2260);
DISPLAY 0.659574 (1660 2260);
PAINT MONO (1660 2260);
DISPLAY INVISIBLE (1660 2260);
FORCEPROP 1 LASTPIN (1650 2250) BN 1
J 0
(1638 2258);
DISPLAY 0.680851 (1638 2258);
PAINT GREEN (1638 2258);
FORCEPROP 2 LAST CDS_LIB standard
J 0
(1700 2250);
DISPLAY INVISIBLE (1700 2250);
FORCEPROP 1 LAST BODY_TYPE PLUMBING
J 0
(1700 2300);
DISPLAY 0.872340 (1700 2300);
PAINT GREEN (1700 2300);
DISPLAY INVISIBLE (1700 2300);
FORCEPROP 1 LAST HDL_TAP TRUE
J 0
(2025 2125);
DISPLAY 0.872340 (2025 2125);
DISPLAY INVISIBLE (2025 2125);
FORCEPROP 1 LAST PATH I131
J 0
(1698 2250);
DISPLAY 0.872340 (1698 2250);
PAINT GREEN (1698 2250);
DISPLAY INVISIBLE (1698 2250);
FORCEADD TAP..1
(1525 2500);
FORCEPROP 3 LASTPIN (1475 2500) SIG_NAME M_C_CPU0_SB_DQS_DP<3>
J 0
(1485 2510);
DISPLAY 0.659574 (1485 2510);
PAINT MONO (1485 2510);
DISPLAY INVISIBLE (1485 2510);
FORCEPROP 1 LASTPIN (1475 2500) BN 3
J 0
(1463 2508);
DISPLAY 0.680851 (1463 2508);
PAINT GREEN (1463 2508);
FORCEPROP 2 LAST CDS_LIB standard
J 0
(1525 2500);
PAINT MONO (1525 2500);
DISPLAY INVISIBLE (1525 2500);
FORCEPROP 1 LAST BODY_TYPE PLUMBING
J 0
(1525 2550);
DISPLAY 0.872340 (1525 2550);
PAINT GREEN (1525 2550);
DISPLAY INVISIBLE (1525 2550);
FORCEPROP 1 LAST HDL_TAP TRUE
J 0
(1850 2375);
DISPLAY 0.872340 (1850 2375);
DISPLAY INVISIBLE (1850 2375);
FORCEPROP 1 LAST PATH I132
J 0
(1523 2500);
DISPLAY 0.872340 (1523 2500);
PAINT GREEN (1523 2500);
DISPLAY INVISIBLE (1523 2500);
FORCEADD TAP..1
(1525 2300);
FORCEPROP 3 LASTPIN (1475 2300) SIG_NAME M_C_CPU0_SB_DQS_DP<1>
J 0
(1485 2310);
DISPLAY 0.659574 (1485 2310);
PAINT MONO (1485 2310);
DISPLAY INVISIBLE (1485 2310);
FORCEPROP 1 LASTPIN (1475 2300) BN 1
J 0
(1463 2308);
DISPLAY 0.680851 (1463 2308);
PAINT GREEN (1463 2308);
FORCEPROP 2 LAST CDS_LIB standard
J 0
(1525 2300);
DISPLAY INVISIBLE (1525 2300);
FORCEPROP 1 LAST BODY_TYPE PLUMBING
J 0
(1525 2350);
DISPLAY 0.872340 (1525 2350);
PAINT GREEN (1525 2350);
DISPLAY INVISIBLE (1525 2350);
FORCEPROP 1 LAST HDL_TAP TRUE
J 0
(1850 2175);
DISPLAY 0.872340 (1850 2175);
DISPLAY INVISIBLE (1850 2175);
FORCEPROP 1 LAST PATH I133
J 0
(1523 2300);
DISPLAY 0.872340 (1523 2300);
PAINT GREEN (1523 2300);
DISPLAY INVISIBLE (1523 2300);
FORCEADD TAP..1
(1525 2400);
FORCEPROP 3 LASTPIN (1475 2400) SIG_NAME M_C_CPU0_SB_DQS_DP<2>
J 0
(1485 2410);
DISPLAY 0.659574 (1485 2410);
PAINT MONO (1485 2410);
DISPLAY INVISIBLE (1485 2410);
FORCEPROP 1 LASTPIN (1475 2400) BN 2
J 0
(1463 2408);
DISPLAY 0.680851 (1463 2408);
PAINT GREEN (1463 2408);
FORCEPROP 2 LAST CDS_LIB standard
J 0
(1525 2400);
DISPLAY INVISIBLE (1525 2400);
FORCEPROP 1 LAST BODY_TYPE PLUMBING
J 0
(1525 2450);
DISPLAY 0.872340 (1525 2450);
PAINT GREEN (1525 2450);
DISPLAY INVISIBLE (1525 2450);
FORCEPROP 1 LAST HDL_TAP TRUE
J 0
(1850 2275);
DISPLAY 0.872340 (1850 2275);
DISPLAY INVISIBLE (1850 2275);
FORCEPROP 1 LAST PATH I134
J 0
(1523 2400);
DISPLAY 0.872340 (1523 2400);
PAINT GREEN (1523 2400);
DISPLAY INVISIBLE (1523 2400);
FORCEADD TAP..1
(1525 2800);
FORCEPROP 3 LASTPIN (1475 2800) SIG_NAME M_C_CPU0_SB_DQS_DP<6>
J 0
(1485 2810);
DISPLAY 0.659574 (1485 2810);
PAINT MONO (1485 2810);
DISPLAY INVISIBLE (1485 2810);
FORCEPROP 1 LASTPIN (1475 2800) BN 6
J 0
(1463 2808);
DISPLAY 0.680851 (1463 2808);
PAINT GREEN (1463 2808);
FORCEPROP 2 LAST CDS_LIB standard
J 0
(1525 2800);
DISPLAY INVISIBLE (1525 2800);
FORCEPROP 1 LAST BODY_TYPE PLUMBING
J 0
(1525 2850);
DISPLAY 0.872340 (1525 2850);
PAINT GREEN (1525 2850);
DISPLAY INVISIBLE (1525 2850);
FORCEPROP 1 LAST HDL_TAP TRUE
J 0
(1850 2675);
DISPLAY 0.872340 (1850 2675);
DISPLAY INVISIBLE (1850 2675);
FORCEPROP 1 LAST PATH I135
J 0
(1523 2800);
DISPLAY 0.872340 (1523 2800);
PAINT GREEN (1523 2800);
DISPLAY INVISIBLE (1523 2800);
FORCEADD TAP..1
(1525 2700);
FORCEPROP 3 LASTPIN (1475 2700) SIG_NAME M_C_CPU0_SB_DQS_DP<5>
J 0
(1485 2710);
DISPLAY 0.659574 (1485 2710);
PAINT MONO (1485 2710);
DISPLAY INVISIBLE (1485 2710);
FORCEPROP 1 LASTPIN (1475 2700) BN 5
J 0
(1463 2708);
DISPLAY 0.680851 (1463 2708);
PAINT GREEN (1463 2708);
FORCEPROP 2 LAST CDS_LIB standard
J 0
(1525 2700);
DISPLAY INVISIBLE (1525 2700);
FORCEPROP 1 LAST BODY_TYPE PLUMBING
J 0
(1525 2750);
DISPLAY 0.872340 (1525 2750);
PAINT GREEN (1525 2750);
DISPLAY INVISIBLE (1525 2750);
FORCEPROP 1 LAST HDL_TAP TRUE
J 0
(1850 2575);
DISPLAY 0.872340 (1850 2575);
DISPLAY INVISIBLE (1850 2575);
FORCEPROP 1 LAST PATH I136
J 0
(1523 2700);
DISPLAY 0.872340 (1523 2700);
PAINT GREEN (1523 2700);
DISPLAY INVISIBLE (1523 2700);
FORCEADD TAP..1
(1525 2600);
FORCEPROP 3 LASTPIN (1475 2600) SIG_NAME M_C_CPU0_SB_DQS_DP<4>
J 0
(1485 2610);
DISPLAY 0.659574 (1485 2610);
PAINT MONO (1485 2610);
DISPLAY INVISIBLE (1485 2610);
FORCEPROP 1 LASTPIN (1475 2600) BN 4
J 0
(1463 2608);
DISPLAY 0.680851 (1463 2608);
PAINT GREEN (1463 2608);
FORCEPROP 2 LAST CDS_LIB standard
J 0
(1525 2600);
PAINT MONO (1525 2600);
DISPLAY INVISIBLE (1525 2600);
FORCEPROP 1 LAST BODY_TYPE PLUMBING
J 0
(1525 2650);
DISPLAY 0.872340 (1525 2650);
PAINT GREEN (1525 2650);
DISPLAY INVISIBLE (1525 2650);
FORCEPROP 1 LAST HDL_TAP TRUE
J 0
(1850 2475);
DISPLAY 0.872340 (1850 2475);
DISPLAY INVISIBLE (1850 2475);
FORCEPROP 1 LAST PATH I137
J 0
(1523 2600);
DISPLAY 0.872340 (1523 2600);
PAINT GREEN (1523 2600);
DISPLAY INVISIBLE (1523 2600);
FORCEADD TAP..1
(1525 2900);
FORCEPROP 3 LASTPIN (1475 2900) SIG_NAME M_C_CPU0_SB_DQS_DP<7>
J 0
(1485 2910);
DISPLAY 0.659574 (1485 2910);
PAINT MONO (1485 2910);
DISPLAY INVISIBLE (1485 2910);
FORCEPROP 1 LASTPIN (1475 2900) BN 7
J 0
(1463 2908);
DISPLAY 0.680851 (1463 2908);
PAINT GREEN (1463 2908);
FORCEPROP 2 LAST CDS_LIB standard
J 0
(1525 2900);
DISPLAY INVISIBLE (1525 2900);
FORCEPROP 1 LAST BODY_TYPE PLUMBING
J 0
(1525 2950);
DISPLAY 0.872340 (1525 2950);
PAINT GREEN (1525 2950);
DISPLAY INVISIBLE (1525 2950);
FORCEPROP 1 LAST HDL_TAP TRUE
J 0
(1850 2775);
DISPLAY 0.872340 (1850 2775);
DISPLAY INVISIBLE (1850 2775);
FORCEPROP 1 LAST PATH I138
J 0
(1523 2900);
DISPLAY 0.872340 (1523 2900);
PAINT GREEN (1523 2900);
DISPLAY INVISIBLE (1523 2900);
FORCEADD TAP..1
(1525 3000);
FORCEPROP 3 LASTPIN (1475 3000) SIG_NAME M_C_CPU0_SB_DQS_DP<8>
J 0
(1485 3010);
DISPLAY 0.659574 (1485 3010);
PAINT MONO (1485 3010);
DISPLAY INVISIBLE (1485 3010);
FORCEPROP 1 LASTPIN (1475 3000) BN 8
J 0
(1463 3008);
DISPLAY 0.680851 (1463 3008);
PAINT GREEN (1463 3008);
FORCEPROP 2 LAST CDS_LIB standard
J 0
(1525 3000);
DISPLAY INVISIBLE (1525 3000);
FORCEPROP 1 LAST BODY_TYPE PLUMBING
J 0
(1525 3050);
DISPLAY 0.872340 (1525 3050);
PAINT GREEN (1525 3050);
DISPLAY INVISIBLE (1525 3050);
FORCEPROP 1 LAST HDL_TAP TRUE
J 0
(1850 2875);
DISPLAY 0.872340 (1850 2875);
DISPLAY INVISIBLE (1850 2875);
FORCEPROP 1 LAST PATH I139
J 0
(1523 3000);
DISPLAY 0.872340 (1523 3000);
PAINT GREEN (1523 3000);
DISPLAY INVISIBLE (1523 3000);
FORCEADD OFFPAGE..1
(-3800 3000);
FORCEPROP 2 LAST $XR0 22 
J 0
(-4021 3000);
DISPLAY 0.638298 (-4021 3000);
PAINT MONO (-4021 3000);
FORCEPROP 2 LAST CDS_LIB standard
J 0
(-3800 3000);
PAINT MONO (-3800 3000);
DISPLAY INVISIBLE (-3800 3000);
FORCEPROP 1 LAST OFFPAGE TRUE
J 0
(-3475 2875);
DISPLAY 0.872340 (-3475 2875);
DISPLAY INVISIBLE (-3475 2875);
FORCEPROP 1 LAST COMMENT_BODY TRUE
J 0
(-3675 2900);
DISPLAY 0.872340 (-3675 2900);
PAINT GREEN (-3675 2900);
DISPLAY INVISIBLE (-3675 2900);
FORCEPROP 2 LAST PATH I14
J 0
(-3750 3075);
DISPLAY 1.021277 (-3750 3075);
DISPLAY INVISIBLE (-3750 3075);
FORCEADD TAP..1
(1525 3250);
FORCEPROP 3 LASTPIN (1475 3250) SIG_NAME M_C_CPU0_SA_DQS_DP<0>
J 0
(1485 3260);
DISPLAY 0.659574 (1485 3260);
PAINT MONO (1485 3260);
DISPLAY INVISIBLE (1485 3260);
FORCEPROP 1 LASTPIN (1475 3250) BN 0
J 0
(1463 3258);
DISPLAY 0.680851 (1463 3258);
PAINT GREEN (1463 3258);
FORCEPROP 2 LAST CDS_LIB standard
J 0
(1525 3250);
PAINT MONO (1525 3250);
DISPLAY INVISIBLE (1525 3250);
FORCEPROP 1 LAST BODY_TYPE PLUMBING
J 0
(1525 3300);
DISPLAY 0.872340 (1525 3300);
PAINT GREEN (1525 3300);
DISPLAY INVISIBLE (1525 3300);
FORCEPROP 1 LAST HDL_TAP TRUE
J 0
(1850 3125);
DISPLAY 0.872340 (1850 3125);
DISPLAY INVISIBLE (1850 3125);
FORCEPROP 1 LAST PATH I140
J 0
(1523 3250);
DISPLAY 0.872340 (1523 3250);
PAINT GREEN (1523 3250);
DISPLAY INVISIBLE (1523 3250);
FORCEADD TAP..1
(1525 3100);
FORCEPROP 3 LASTPIN (1475 3100) SIG_NAME M_C_CPU0_SB_DQS_DP<9>
J 0
(1485 3110);
DISPLAY 0.659574 (1485 3110);
PAINT MONO (1485 3110);
DISPLAY INVISIBLE (1485 3110);
FORCEPROP 1 LASTPIN (1475 3100) BN 9
J 0
(1463 3108);
DISPLAY 0.680851 (1463 3108);
PAINT GREEN (1463 3108);
FORCEPROP 2 LAST CDS_LIB standard
J 0
(1525 3100);
DISPLAY INVISIBLE (1525 3100);
FORCEPROP 1 LAST BODY_TYPE PLUMBING
J 0
(1525 3150);
DISPLAY 0.872340 (1525 3150);
PAINT GREEN (1525 3150);
DISPLAY INVISIBLE (1525 3150);
FORCEPROP 1 LAST HDL_TAP TRUE
J 0
(1850 2975);
DISPLAY 0.872340 (1850 2975);
DISPLAY INVISIBLE (1850 2975);
FORCEPROP 1 LAST PATH I141
J 0
(1523 3100);
DISPLAY 0.872340 (1523 3100);
PAINT GREEN (1523 3100);
DISPLAY INVISIBLE (1523 3100);
FORCEADD TAP..1
(1700 2350);
FORCEPROP 3 LASTPIN (1650 2350) SIG_NAME M_C_CPU0_SB_DQS_DN<2>
J 0
(1660 2360);
DISPLAY 0.659574 (1660 2360);
PAINT MONO (1660 2360);
DISPLAY INVISIBLE (1660 2360);
FORCEPROP 1 LASTPIN (1650 2350) BN 2
J 0
(1638 2358);
DISPLAY 0.680851 (1638 2358);
PAINT GREEN (1638 2358);
FORCEPROP 2 LAST CDS_LIB standard
J 0
(1700 2350);
DISPLAY INVISIBLE (1700 2350);
FORCEPROP 1 LAST BODY_TYPE PLUMBING
J 0
(1700 2400);
DISPLAY 0.872340 (1700 2400);
PAINT GREEN (1700 2400);
DISPLAY INVISIBLE (1700 2400);
FORCEPROP 1 LAST HDL_TAP TRUE
J 0
(2025 2225);
DISPLAY 0.872340 (2025 2225);
DISPLAY INVISIBLE (2025 2225);
FORCEPROP 1 LAST PATH I142
J 0
(1698 2350);
DISPLAY 0.872340 (1698 2350);
PAINT GREEN (1698 2350);
DISPLAY INVISIBLE (1698 2350);
FORCEADD TAP..1
(1700 2550);
FORCEPROP 3 LASTPIN (1650 2550) SIG_NAME M_C_CPU0_SB_DQS_DN<4>
J 0
(1660 2560);
DISPLAY 0.659574 (1660 2560);
PAINT MONO (1660 2560);
DISPLAY INVISIBLE (1660 2560);
FORCEPROP 1 LASTPIN (1650 2550) BN 4
J 0
(1638 2558);
DISPLAY 0.680851 (1638 2558);
PAINT GREEN (1638 2558);
FORCEPROP 2 LAST CDS_LIB standard
J 0
(1700 2550);
PAINT MONO (1700 2550);
DISPLAY INVISIBLE (1700 2550);
FORCEPROP 1 LAST BODY_TYPE PLUMBING
J 0
(1700 2600);
DISPLAY 0.872340 (1700 2600);
PAINT GREEN (1700 2600);
DISPLAY INVISIBLE (1700 2600);
FORCEPROP 1 LAST HDL_TAP TRUE
J 0
(2025 2425);
DISPLAY 0.872340 (2025 2425);
DISPLAY INVISIBLE (2025 2425);
FORCEPROP 1 LAST PATH I143
J 0
(1698 2550);
DISPLAY 0.872340 (1698 2550);
PAINT GREEN (1698 2550);
DISPLAY INVISIBLE (1698 2550);
FORCEADD TAP..1
(1700 2450);
FORCEPROP 3 LASTPIN (1650 2450) SIG_NAME M_C_CPU0_SB_DQS_DN<3>
J 0
(1660 2460);
DISPLAY 0.659574 (1660 2460);
PAINT MONO (1660 2460);
DISPLAY INVISIBLE (1660 2460);
FORCEPROP 1 LASTPIN (1650 2450) BN 3
J 0
(1638 2458);
DISPLAY 0.680851 (1638 2458);
PAINT GREEN (1638 2458);
FORCEPROP 2 LAST CDS_LIB standard
J 0
(1700 2450);
PAINT MONO (1700 2450);
DISPLAY INVISIBLE (1700 2450);
FORCEPROP 1 LAST BODY_TYPE PLUMBING
J 0
(1700 2500);
DISPLAY 0.872340 (1700 2500);
PAINT GREEN (1700 2500);
DISPLAY INVISIBLE (1700 2500);
FORCEPROP 1 LAST HDL_TAP TRUE
J 0
(2025 2325);
DISPLAY 0.872340 (2025 2325);
DISPLAY INVISIBLE (2025 2325);
FORCEPROP 1 LAST PATH I144
J 0
(1698 2450);
DISPLAY 0.872340 (1698 2450);
PAINT GREEN (1698 2450);
DISPLAY INVISIBLE (1698 2450);
FORCEADD TAP..1
(1700 2650);
FORCEPROP 3 LASTPIN (1650 2650) SIG_NAME M_C_CPU0_SB_DQS_DN<5>
J 0
(1660 2660);
DISPLAY 0.659574 (1660 2660);
PAINT MONO (1660 2660);
DISPLAY INVISIBLE (1660 2660);
FORCEPROP 1 LASTPIN (1650 2650) BN 5
J 0
(1638 2658);
DISPLAY 0.680851 (1638 2658);
PAINT GREEN (1638 2658);
FORCEPROP 2 LAST CDS_LIB standard
J 0
(1700 2650);
DISPLAY INVISIBLE (1700 2650);
FORCEPROP 1 LAST BODY_TYPE PLUMBING
J 0
(1700 2700);
DISPLAY 0.872340 (1700 2700);
PAINT GREEN (1700 2700);
DISPLAY INVISIBLE (1700 2700);
FORCEPROP 1 LAST HDL_TAP TRUE
J 0
(2025 2525);
DISPLAY 0.872340 (2025 2525);
DISPLAY INVISIBLE (2025 2525);
FORCEPROP 1 LAST PATH I145
J 0
(1698 2650);
DISPLAY 0.872340 (1698 2650);
PAINT GREEN (1698 2650);
DISPLAY INVISIBLE (1698 2650);
FORCEADD TAP..1
(1700 2750);
FORCEPROP 3 LASTPIN (1650 2750) SIG_NAME M_C_CPU0_SB_DQS_DN<6>
J 0
(1660 2760);
DISPLAY 0.659574 (1660 2760);
PAINT MONO (1660 2760);
DISPLAY INVISIBLE (1660 2760);
FORCEPROP 1 LASTPIN (1650 2750) BN 6
J 0
(1638 2758);
DISPLAY 0.680851 (1638 2758);
PAINT GREEN (1638 2758);
FORCEPROP 2 LAST CDS_LIB standard
J 0
(1700 2750);
DISPLAY INVISIBLE (1700 2750);
FORCEPROP 1 LAST BODY_TYPE PLUMBING
J 0
(1700 2800);
DISPLAY 0.872340 (1700 2800);
PAINT GREEN (1700 2800);
DISPLAY INVISIBLE (1700 2800);
FORCEPROP 1 LAST HDL_TAP TRUE
J 0
(2025 2625);
DISPLAY 0.872340 (2025 2625);
DISPLAY INVISIBLE (2025 2625);
FORCEPROP 1 LAST PATH I146
J 0
(1698 2750);
DISPLAY 0.872340 (1698 2750);
PAINT GREEN (1698 2750);
DISPLAY INVISIBLE (1698 2750);
FORCEADD TAP..1
(1700 2850);
FORCEPROP 3 LASTPIN (1650 2850) SIG_NAME M_C_CPU0_SB_DQS_DN<7>
J 0
(1660 2860);
DISPLAY 0.659574 (1660 2860);
PAINT MONO (1660 2860);
DISPLAY INVISIBLE (1660 2860);
FORCEPROP 1 LASTPIN (1650 2850) BN 7
J 0
(1638 2858);
DISPLAY 0.680851 (1638 2858);
PAINT GREEN (1638 2858);
FORCEPROP 2 LAST CDS_LIB standard
J 0
(1700 2850);
DISPLAY INVISIBLE (1700 2850);
FORCEPROP 1 LAST BODY_TYPE PLUMBING
J 0
(1700 2900);
DISPLAY 0.872340 (1700 2900);
PAINT GREEN (1700 2900);
DISPLAY INVISIBLE (1700 2900);
FORCEPROP 1 LAST HDL_TAP TRUE
J 0
(2025 2725);
DISPLAY 0.872340 (2025 2725);
DISPLAY INVISIBLE (2025 2725);
FORCEPROP 1 LAST PATH I147
J 0
(1698 2850);
DISPLAY 0.872340 (1698 2850);
PAINT GREEN (1698 2850);
DISPLAY INVISIBLE (1698 2850);
FORCEADD TAP..1
(1700 3050);
FORCEPROP 3 LASTPIN (1650 3050) SIG_NAME M_C_CPU0_SB_DQS_DN<9>
J 0
(1660 3060);
DISPLAY 0.659574 (1660 3060);
PAINT MONO (1660 3060);
DISPLAY INVISIBLE (1660 3060);
FORCEPROP 1 LASTPIN (1650 3050) BN 9
J 0
(1638 3058);
DISPLAY 0.680851 (1638 3058);
PAINT GREEN (1638 3058);
FORCEPROP 2 LAST CDS_LIB standard
J 0
(1700 3050);
DISPLAY INVISIBLE (1700 3050);
FORCEPROP 1 LAST BODY_TYPE PLUMBING
J 0
(1700 3100);
DISPLAY 0.872340 (1700 3100);
PAINT GREEN (1700 3100);
DISPLAY INVISIBLE (1700 3100);
FORCEPROP 1 LAST HDL_TAP TRUE
J 0
(2025 2925);
DISPLAY 0.872340 (2025 2925);
DISPLAY INVISIBLE (2025 2925);
FORCEPROP 1 LAST PATH I148
J 0
(1698 3050);
DISPLAY 0.872340 (1698 3050);
PAINT GREEN (1698 3050);
DISPLAY INVISIBLE (1698 3050);
FORCEADD TAP..1
(1700 2950);
FORCEPROP 3 LASTPIN (1650 2950) SIG_NAME M_C_CPU0_SB_DQS_DN<8>
J 0
(1660 2960);
DISPLAY 0.659574 (1660 2960);
PAINT MONO (1660 2960);
DISPLAY INVISIBLE (1660 2960);
FORCEPROP 1 LASTPIN (1650 2950) BN 8
J 0
(1638 2958);
DISPLAY 0.680851 (1638 2958);
PAINT GREEN (1638 2958);
FORCEPROP 2 LAST CDS_LIB standard
J 0
(1700 2950);
DISPLAY INVISIBLE (1700 2950);
FORCEPROP 1 LAST BODY_TYPE PLUMBING
J 0
(1700 3000);
DISPLAY 0.872340 (1700 3000);
PAINT GREEN (1700 3000);
DISPLAY INVISIBLE (1700 3000);
FORCEPROP 1 LAST HDL_TAP TRUE
J 0
(2025 2825);
DISPLAY 0.872340 (2025 2825);
DISPLAY INVISIBLE (2025 2825);
FORCEPROP 1 LAST PATH I149
J 0
(1698 2950);
DISPLAY 0.872340 (1698 2950);
PAINT GREEN (1698 2950);
DISPLAY INVISIBLE (1698 2950);
FORCEADD OFFPAGE..1
(-3800 2900);
FORCEPROP 2 LAST $XR0 22 
J 0
(-4021 2900);
DISPLAY 0.638298 (-4021 2900);
PAINT MONO (-4021 2900);
FORCEPROP 2 LAST CDS_LIB standard
J 0
(-3800 2900);
PAINT MONO (-3800 2900);
DISPLAY INVISIBLE (-3800 2900);
FORCEPROP 1 LAST OFFPAGE TRUE
J 0
(-3475 2775);
DISPLAY 0.872340 (-3475 2775);
DISPLAY INVISIBLE (-3475 2775);
FORCEPROP 1 LAST COMMENT_BODY TRUE
J 0
(-3675 2800);
DISPLAY 0.872340 (-3675 2800);
PAINT GREEN (-3675 2800);
DISPLAY INVISIBLE (-3675 2800);
FORCEPROP 2 LAST PATH I15
J 0
(-3750 2975);
DISPLAY 1.021277 (-3750 2975);
DISPLAY INVISIBLE (-3750 2975);
FORCEADD TAP..1
(1700 3200);
FORCEPROP 3 LASTPIN (1650 3200) SIG_NAME M_C_CPU0_SA_DQS_DN<0>
J 0
(1660 3210);
DISPLAY 0.659574 (1660 3210);
PAINT MONO (1660 3210);
DISPLAY INVISIBLE (1660 3210);
FORCEPROP 1 LASTPIN (1650 3200) BN 0
J 0
(1638 3208);
DISPLAY 0.680851 (1638 3208);
PAINT GREEN (1638 3208);
FORCEPROP 2 LAST CDS_LIB standard
J 0
(1700 3200);
PAINT MONO (1700 3200);
DISPLAY INVISIBLE (1700 3200);
FORCEPROP 1 LAST BODY_TYPE PLUMBING
J 0
(1700 3250);
DISPLAY 0.872340 (1700 3250);
PAINT GREEN (1700 3250);
DISPLAY INVISIBLE (1700 3250);
FORCEPROP 1 LAST HDL_TAP TRUE
J 0
(2025 3075);
DISPLAY 0.872340 (2025 3075);
DISPLAY INVISIBLE (2025 3075);
FORCEPROP 1 LAST PATH I150
J 0
(1698 3200);
DISPLAY 0.872340 (1698 3200);
PAINT GREEN (1698 3200);
DISPLAY INVISIBLE (1698 3200);
FORCEADD TAP..1
(1700 3300);
FORCEPROP 3 LASTPIN (1650 3300) SIG_NAME M_C_CPU0_SA_DQS_DN<1>
J 0
(1660 3310);
DISPLAY 0.659574 (1660 3310);
PAINT MONO (1660 3310);
DISPLAY INVISIBLE (1660 3310);
FORCEPROP 1 LASTPIN (1650 3300) BN 1
J 0
(1638 3308);
DISPLAY 0.680851 (1638 3308);
PAINT GREEN (1638 3308);
FORCEPROP 2 LAST CDS_LIB standard
J 0
(1700 3300);
DISPLAY INVISIBLE (1700 3300);
FORCEPROP 1 LAST BODY_TYPE PLUMBING
J 0
(1700 3350);
DISPLAY 0.872340 (1700 3350);
PAINT GREEN (1700 3350);
DISPLAY INVISIBLE (1700 3350);
FORCEPROP 1 LAST HDL_TAP TRUE
J 0
(2025 3175);
DISPLAY 0.872340 (2025 3175);
DISPLAY INVISIBLE (2025 3175);
FORCEPROP 1 LAST PATH I151
J 0
(1698 3300);
DISPLAY 0.872340 (1698 3300);
PAINT GREEN (1698 3300);
DISPLAY INVISIBLE (1698 3300);
FORCEADD TAP..1
(1525 3550);
FORCEPROP 3 LASTPIN (1475 3550) SIG_NAME M_C_CPU0_SA_DQS_DP<3>
J 0
(1485 3560);
DISPLAY 0.659574 (1485 3560);
PAINT MONO (1485 3560);
DISPLAY INVISIBLE (1485 3560);
FORCEPROP 1 LASTPIN (1475 3550) BN 3
J 0
(1463 3558);
DISPLAY 0.680851 (1463 3558);
PAINT GREEN (1463 3558);
FORCEPROP 2 LAST CDS_LIB standard
J 0
(1525 3550);
PAINT MONO (1525 3550);
DISPLAY INVISIBLE (1525 3550);
FORCEPROP 1 LAST BODY_TYPE PLUMBING
J 0
(1525 3600);
DISPLAY 0.872340 (1525 3600);
PAINT GREEN (1525 3600);
DISPLAY INVISIBLE (1525 3600);
FORCEPROP 1 LAST HDL_TAP TRUE
J 0
(1850 3425);
DISPLAY 0.872340 (1850 3425);
DISPLAY INVISIBLE (1850 3425);
FORCEPROP 1 LAST PATH I152
J 0
(1523 3550);
DISPLAY 0.872340 (1523 3550);
PAINT GREEN (1523 3550);
DISPLAY INVISIBLE (1523 3550);
FORCEADD TAP..1
(1525 3350);
FORCEPROP 3 LASTPIN (1475 3350) SIG_NAME M_C_CPU0_SA_DQS_DP<1>
J 0
(1485 3360);
DISPLAY 0.659574 (1485 3360);
PAINT MONO (1485 3360);
DISPLAY INVISIBLE (1485 3360);
FORCEPROP 1 LASTPIN (1475 3350) BN 1
J 0
(1463 3358);
DISPLAY 0.680851 (1463 3358);
PAINT GREEN (1463 3358);
FORCEPROP 2 LAST CDS_LIB standard
J 0
(1525 3350);
DISPLAY INVISIBLE (1525 3350);
FORCEPROP 1 LAST BODY_TYPE PLUMBING
J 0
(1525 3400);
DISPLAY 0.872340 (1525 3400);
PAINT GREEN (1525 3400);
DISPLAY INVISIBLE (1525 3400);
FORCEPROP 1 LAST HDL_TAP TRUE
J 0
(1850 3225);
DISPLAY 0.872340 (1850 3225);
DISPLAY INVISIBLE (1850 3225);
FORCEPROP 1 LAST PATH I153
J 0
(1523 3350);
DISPLAY 0.872340 (1523 3350);
PAINT GREEN (1523 3350);
DISPLAY INVISIBLE (1523 3350);
FORCEADD TAP..1
(1525 3450);
FORCEPROP 3 LASTPIN (1475 3450) SIG_NAME M_C_CPU0_SA_DQS_DP<2>
J 0
(1485 3460);
DISPLAY 0.659574 (1485 3460);
PAINT MONO (1485 3460);
DISPLAY INVISIBLE (1485 3460);
FORCEPROP 1 LASTPIN (1475 3450) BN 2
J 0
(1463 3458);
DISPLAY 0.680851 (1463 3458);
PAINT GREEN (1463 3458);
FORCEPROP 2 LAST CDS_LIB standard
J 0
(1525 3450);
DISPLAY INVISIBLE (1525 3450);
FORCEPROP 1 LAST BODY_TYPE PLUMBING
J 0
(1525 3500);
DISPLAY 0.872340 (1525 3500);
PAINT GREEN (1525 3500);
DISPLAY INVISIBLE (1525 3500);
FORCEPROP 1 LAST HDL_TAP TRUE
J 0
(1850 3325);
DISPLAY 0.872340 (1850 3325);
DISPLAY INVISIBLE (1850 3325);
FORCEPROP 1 LAST PATH I154
J 0
(1523 3450);
DISPLAY 0.872340 (1523 3450);
PAINT GREEN (1523 3450);
DISPLAY INVISIBLE (1523 3450);
FORCEADD TAP..1
(1525 3750);
FORCEPROP 3 LASTPIN (1475 3750) SIG_NAME M_C_CPU0_SA_DQS_DP<5>
J 0
(1485 3760);
DISPLAY 0.659574 (1485 3760);
PAINT MONO (1485 3760);
DISPLAY INVISIBLE (1485 3760);
FORCEPROP 1 LASTPIN (1475 3750) BN 5
J 0
(1463 3758);
DISPLAY 0.680851 (1463 3758);
PAINT GREEN (1463 3758);
FORCEPROP 2 LAST CDS_LIB standard
J 0
(1525 3750);
DISPLAY INVISIBLE (1525 3750);
FORCEPROP 1 LAST BODY_TYPE PLUMBING
J 0
(1525 3800);
DISPLAY 0.872340 (1525 3800);
PAINT GREEN (1525 3800);
DISPLAY INVISIBLE (1525 3800);
FORCEPROP 1 LAST HDL_TAP TRUE
J 0
(1850 3625);
DISPLAY 0.872340 (1850 3625);
DISPLAY INVISIBLE (1850 3625);
FORCEPROP 1 LAST PATH I155
J 0
(1523 3750);
DISPLAY 0.872340 (1523 3750);
PAINT GREEN (1523 3750);
DISPLAY INVISIBLE (1523 3750);
FORCEADD TAP..1
(1525 3650);
FORCEPROP 3 LASTPIN (1475 3650) SIG_NAME M_C_CPU0_SA_DQS_DP<4>
J 0
(1485 3660);
DISPLAY 0.659574 (1485 3660);
PAINT MONO (1485 3660);
DISPLAY INVISIBLE (1485 3660);
FORCEPROP 1 LASTPIN (1475 3650) BN 4
J 0
(1463 3658);
DISPLAY 0.680851 (1463 3658);
PAINT GREEN (1463 3658);
FORCEPROP 2 LAST CDS_LIB standard
J 0
(1525 3650);
PAINT MONO (1525 3650);
DISPLAY INVISIBLE (1525 3650);
FORCEPROP 1 LAST BODY_TYPE PLUMBING
J 0
(1525 3700);
DISPLAY 0.872340 (1525 3700);
PAINT GREEN (1525 3700);
DISPLAY INVISIBLE (1525 3700);
FORCEPROP 1 LAST HDL_TAP TRUE
J 0
(1850 3525);
DISPLAY 0.872340 (1850 3525);
DISPLAY INVISIBLE (1850 3525);
FORCEPROP 1 LAST PATH I156
J 0
(1523 3650);
DISPLAY 0.872340 (1523 3650);
PAINT GREEN (1523 3650);
DISPLAY INVISIBLE (1523 3650);
FORCEADD TAP..1
(1525 3850);
FORCEPROP 3 LASTPIN (1475 3850) SIG_NAME M_C_CPU0_SA_DQS_DP<6>
J 0
(1485 3860);
DISPLAY 0.659574 (1485 3860);
PAINT MONO (1485 3860);
DISPLAY INVISIBLE (1485 3860);
FORCEPROP 1 LASTPIN (1475 3850) BN 6
J 0
(1463 3858);
DISPLAY 0.680851 (1463 3858);
PAINT GREEN (1463 3858);
FORCEPROP 2 LAST CDS_LIB standard
J 0
(1525 3850);
DISPLAY INVISIBLE (1525 3850);
FORCEPROP 1 LAST BODY_TYPE PLUMBING
J 0
(1525 3900);
DISPLAY 0.872340 (1525 3900);
PAINT GREEN (1525 3900);
DISPLAY INVISIBLE (1525 3900);
FORCEPROP 1 LAST HDL_TAP TRUE
J 0
(1850 3725);
DISPLAY 0.872340 (1850 3725);
DISPLAY INVISIBLE (1850 3725);
FORCEPROP 1 LAST PATH I157
J 0
(1523 3850);
DISPLAY 0.872340 (1523 3850);
PAINT GREEN (1523 3850);
DISPLAY INVISIBLE (1523 3850);
FORCEADD TAP..1
(1525 3950);
FORCEPROP 3 LASTPIN (1475 3950) SIG_NAME M_C_CPU0_SA_DQS_DP<7>
J 0
(1485 3960);
DISPLAY 0.659574 (1485 3960);
PAINT MONO (1485 3960);
DISPLAY INVISIBLE (1485 3960);
FORCEPROP 1 LASTPIN (1475 3950) BN 7
J 0
(1463 3958);
DISPLAY 0.680851 (1463 3958);
PAINT GREEN (1463 3958);
FORCEPROP 2 LAST CDS_LIB standard
J 0
(1525 3950);
DISPLAY INVISIBLE (1525 3950);
FORCEPROP 1 LAST BODY_TYPE PLUMBING
J 0
(1525 4000);
DISPLAY 0.872340 (1525 4000);
PAINT GREEN (1525 4000);
DISPLAY INVISIBLE (1525 4000);
FORCEPROP 1 LAST HDL_TAP TRUE
J 0
(1850 3825);
DISPLAY 0.872340 (1850 3825);
DISPLAY INVISIBLE (1850 3825);
FORCEPROP 1 LAST PATH I158
J 0
(1523 3950);
DISPLAY 0.872340 (1523 3950);
PAINT GREEN (1523 3950);
DISPLAY INVISIBLE (1523 3950);
FORCEADD TAP..1
(1525 4050);
FORCEPROP 3 LASTPIN (1475 4050) SIG_NAME M_C_CPU0_SA_DQS_DP<8>
J 0
(1485 4060);
DISPLAY 0.659574 (1485 4060);
PAINT MONO (1485 4060);
DISPLAY INVISIBLE (1485 4060);
FORCEPROP 1 LASTPIN (1475 4050) BN 8
J 0
(1463 4058);
DISPLAY 0.680851 (1463 4058);
PAINT GREEN (1463 4058);
FORCEPROP 2 LAST CDS_LIB standard
J 0
(1525 4050);
DISPLAY INVISIBLE (1525 4050);
FORCEPROP 1 LAST BODY_TYPE PLUMBING
J 0
(1525 4100);
DISPLAY 0.872340 (1525 4100);
PAINT GREEN (1525 4100);
DISPLAY INVISIBLE (1525 4100);
FORCEPROP 1 LAST HDL_TAP TRUE
J 0
(1850 3925);
DISPLAY 0.872340 (1850 3925);
DISPLAY INVISIBLE (1850 3925);
FORCEPROP 1 LAST PATH I159
J 0
(1523 4050);
DISPLAY 0.872340 (1523 4050);
PAINT GREEN (1523 4050);
DISPLAY INVISIBLE (1523 4050);
FORCEADD OFFPAGE..1
(-3800 2850);
FORCEPROP 2 LAST $XR0 22 
J 0
(-4021 2850);
DISPLAY 0.638298 (-4021 2850);
PAINT MONO (-4021 2850);
FORCEPROP 2 LAST CDS_LIB standard
J 0
(-3800 2850);
PAINT MONO (-3800 2850);
DISPLAY INVISIBLE (-3800 2850);
FORCEPROP 1 LAST OFFPAGE TRUE
J 0
(-3475 2725);
DISPLAY 0.872340 (-3475 2725);
DISPLAY INVISIBLE (-3475 2725);
FORCEPROP 1 LAST COMMENT_BODY TRUE
J 0
(-3675 2750);
DISPLAY 0.872340 (-3675 2750);
PAINT GREEN (-3675 2750);
DISPLAY INVISIBLE (-3675 2750);
FORCEPROP 2 LAST PATH I16
J 0
(-3750 2925);
DISPLAY 1.021277 (-3750 2925);
DISPLAY INVISIBLE (-3750 2925);
FORCEADD TAP..1
(1525 4150);
FORCEPROP 3 LASTPIN (1475 4150) SIG_NAME M_C_CPU0_SA_DQS_DP<9>
J 0
(1485 4160);
DISPLAY 0.659574 (1485 4160);
PAINT MONO (1485 4160);
DISPLAY INVISIBLE (1485 4160);
FORCEPROP 1 LASTPIN (1475 4150) BN 9
J 0
(1463 4158);
DISPLAY 0.680851 (1463 4158);
PAINT GREEN (1463 4158);
FORCEPROP 2 LAST CDS_LIB standard
J 0
(1525 4150);
DISPLAY INVISIBLE (1525 4150);
FORCEPROP 1 LAST BODY_TYPE PLUMBING
J 0
(1525 4200);
DISPLAY 0.872340 (1525 4200);
PAINT GREEN (1525 4200);
DISPLAY INVISIBLE (1525 4200);
FORCEPROP 1 LAST HDL_TAP TRUE
J 0
(1850 4025);
DISPLAY 0.872340 (1850 4025);
DISPLAY INVISIBLE (1850 4025);
FORCEPROP 1 LAST PATH I160
J 0
(1523 4150);
DISPLAY 0.872340 (1523 4150);
PAINT GREEN (1523 4150);
DISPLAY INVISIBLE (1523 4150);
FORCEADD TAP..1
(1700 3500);
FORCEPROP 3 LASTPIN (1650 3500) SIG_NAME M_C_CPU0_SA_DQS_DN<3>
J 0
(1660 3510);
DISPLAY 0.659574 (1660 3510);
PAINT MONO (1660 3510);
DISPLAY INVISIBLE (1660 3510);
FORCEPROP 1 LASTPIN (1650 3500) BN 3
J 0
(1638 3508);
DISPLAY 0.680851 (1638 3508);
PAINT GREEN (1638 3508);
FORCEPROP 2 LAST CDS_LIB standard
J 0
(1700 3500);
PAINT MONO (1700 3500);
DISPLAY INVISIBLE (1700 3500);
FORCEPROP 1 LAST BODY_TYPE PLUMBING
J 0
(1700 3550);
DISPLAY 0.872340 (1700 3550);
PAINT GREEN (1700 3550);
DISPLAY INVISIBLE (1700 3550);
FORCEPROP 1 LAST HDL_TAP TRUE
J 0
(2025 3375);
DISPLAY 0.872340 (2025 3375);
DISPLAY INVISIBLE (2025 3375);
FORCEPROP 1 LAST PATH I161
J 0
(1698 3500);
DISPLAY 0.872340 (1698 3500);
PAINT GREEN (1698 3500);
DISPLAY INVISIBLE (1698 3500);
FORCEADD TAP..1
(1700 3400);
FORCEPROP 3 LASTPIN (1650 3400) SIG_NAME M_C_CPU0_SA_DQS_DN<2>
J 0
(1660 3410);
DISPLAY 0.659574 (1660 3410);
PAINT MONO (1660 3410);
DISPLAY INVISIBLE (1660 3410);
FORCEPROP 1 LASTPIN (1650 3400) BN 2
J 0
(1638 3408);
DISPLAY 0.680851 (1638 3408);
PAINT GREEN (1638 3408);
FORCEPROP 2 LAST CDS_LIB standard
J 0
(1700 3400);
DISPLAY INVISIBLE (1700 3400);
FORCEPROP 1 LAST BODY_TYPE PLUMBING
J 0
(1700 3450);
DISPLAY 0.872340 (1700 3450);
PAINT GREEN (1700 3450);
DISPLAY INVISIBLE (1700 3450);
FORCEPROP 1 LAST HDL_TAP TRUE
J 0
(2025 3275);
DISPLAY 0.872340 (2025 3275);
DISPLAY INVISIBLE (2025 3275);
FORCEPROP 1 LAST PATH I162
J 0
(1698 3400);
DISPLAY 0.872340 (1698 3400);
PAINT GREEN (1698 3400);
DISPLAY INVISIBLE (1698 3400);
FORCEADD TAP..1
(1700 3600);
FORCEPROP 3 LASTPIN (1650 3600) SIG_NAME M_C_CPU0_SA_DQS_DN<4>
J 0
(1660 3610);
DISPLAY 0.659574 (1660 3610);
PAINT MONO (1660 3610);
DISPLAY INVISIBLE (1660 3610);
FORCEPROP 1 LASTPIN (1650 3600) BN 4
J 0
(1638 3608);
DISPLAY 0.680851 (1638 3608);
PAINT GREEN (1638 3608);
FORCEPROP 2 LAST CDS_LIB standard
J 0
(1700 3600);
PAINT MONO (1700 3600);
DISPLAY INVISIBLE (1700 3600);
FORCEPROP 1 LAST BODY_TYPE PLUMBING
J 0
(1700 3650);
DISPLAY 0.872340 (1700 3650);
PAINT GREEN (1700 3650);
DISPLAY INVISIBLE (1700 3650);
FORCEPROP 1 LAST HDL_TAP TRUE
J 0
(2025 3475);
DISPLAY 0.872340 (2025 3475);
DISPLAY INVISIBLE (2025 3475);
FORCEPROP 1 LAST PATH I163
J 0
(1698 3600);
DISPLAY 0.872340 (1698 3600);
PAINT GREEN (1698 3600);
DISPLAY INVISIBLE (1698 3600);
FORCEADD TAP..1
(1700 3700);
FORCEPROP 3 LASTPIN (1650 3700) SIG_NAME M_C_CPU0_SA_DQS_DN<5>
J 0
(1660 3710);
DISPLAY 0.659574 (1660 3710);
PAINT MONO (1660 3710);
DISPLAY INVISIBLE (1660 3710);
FORCEPROP 1 LASTPIN (1650 3700) BN 5
J 0
(1638 3708);
DISPLAY 0.680851 (1638 3708);
PAINT GREEN (1638 3708);
FORCEPROP 2 LAST CDS_LIB standard
J 0
(1700 3700);
DISPLAY INVISIBLE (1700 3700);
FORCEPROP 1 LAST BODY_TYPE PLUMBING
J 0
(1700 3750);
DISPLAY 0.872340 (1700 3750);
PAINT GREEN (1700 3750);
DISPLAY INVISIBLE (1700 3750);
FORCEPROP 1 LAST HDL_TAP TRUE
J 0
(2025 3575);
DISPLAY 0.872340 (2025 3575);
DISPLAY INVISIBLE (2025 3575);
FORCEPROP 1 LAST PATH I164
J 0
(1698 3700);
DISPLAY 0.872340 (1698 3700);
PAINT GREEN (1698 3700);
DISPLAY INVISIBLE (1698 3700);
FORCEADD TAP..1
(1700 3800);
FORCEPROP 3 LASTPIN (1650 3800) SIG_NAME M_C_CPU0_SA_DQS_DN<6>
J 0
(1660 3810);
DISPLAY 0.659574 (1660 3810);
PAINT MONO (1660 3810);
DISPLAY INVISIBLE (1660 3810);
FORCEPROP 1 LASTPIN (1650 3800) BN 6
J 0
(1638 3808);
DISPLAY 0.680851 (1638 3808);
PAINT GREEN (1638 3808);
FORCEPROP 2 LAST CDS_LIB standard
J 0
(1700 3800);
DISPLAY INVISIBLE (1700 3800);
FORCEPROP 1 LAST BODY_TYPE PLUMBING
J 0
(1700 3850);
DISPLAY 0.872340 (1700 3850);
PAINT GREEN (1700 3850);
DISPLAY INVISIBLE (1700 3850);
FORCEPROP 1 LAST HDL_TAP TRUE
J 0
(2025 3675);
DISPLAY 0.872340 (2025 3675);
DISPLAY INVISIBLE (2025 3675);
FORCEPROP 1 LAST PATH I165
J 0
(1698 3800);
DISPLAY 0.872340 (1698 3800);
PAINT GREEN (1698 3800);
DISPLAY INVISIBLE (1698 3800);
FORCEADD TAP..1
(1700 3900);
FORCEPROP 3 LASTPIN (1650 3900) SIG_NAME M_C_CPU0_SA_DQS_DN<7>
J 0
(1660 3910);
DISPLAY 0.659574 (1660 3910);
PAINT MONO (1660 3910);
DISPLAY INVISIBLE (1660 3910);
FORCEPROP 1 LASTPIN (1650 3900) BN 7
J 0
(1638 3908);
DISPLAY 0.680851 (1638 3908);
PAINT GREEN (1638 3908);
FORCEPROP 2 LAST CDS_LIB standard
J 0
(1700 3900);
DISPLAY INVISIBLE (1700 3900);
FORCEPROP 1 LAST BODY_TYPE PLUMBING
J 0
(1700 3950);
DISPLAY 0.872340 (1700 3950);
PAINT GREEN (1700 3950);
DISPLAY INVISIBLE (1700 3950);
FORCEPROP 1 LAST HDL_TAP TRUE
J 0
(2025 3775);
DISPLAY 0.872340 (2025 3775);
DISPLAY INVISIBLE (2025 3775);
FORCEPROP 1 LAST PATH I166
J 0
(1698 3900);
DISPLAY 0.872340 (1698 3900);
PAINT GREEN (1698 3900);
DISPLAY INVISIBLE (1698 3900);
FORCEADD TAP..1
(1700 4000);
FORCEPROP 3 LASTPIN (1650 4000) SIG_NAME M_C_CPU0_SA_DQS_DN<8>
J 0
(1660 4010);
DISPLAY 0.659574 (1660 4010);
PAINT MONO (1660 4010);
DISPLAY INVISIBLE (1660 4010);
FORCEPROP 1 LASTPIN (1650 4000) BN 8
J 0
(1638 4008);
DISPLAY 0.680851 (1638 4008);
PAINT GREEN (1638 4008);
FORCEPROP 2 LAST CDS_LIB standard
J 0
(1700 4000);
DISPLAY INVISIBLE (1700 4000);
FORCEPROP 1 LAST BODY_TYPE PLUMBING
J 0
(1700 4050);
DISPLAY 0.872340 (1700 4050);
PAINT GREEN (1700 4050);
DISPLAY INVISIBLE (1700 4050);
FORCEPROP 1 LAST HDL_TAP TRUE
J 0
(2025 3875);
DISPLAY 0.872340 (2025 3875);
DISPLAY INVISIBLE (2025 3875);
FORCEPROP 1 LAST PATH I167
J 0
(1698 4000);
DISPLAY 0.872340 (1698 4000);
PAINT GREEN (1698 4000);
DISPLAY INVISIBLE (1698 4000);
FORCEADD TAP..1
(1700 4100);
FORCEPROP 3 LASTPIN (1650 4100) SIG_NAME M_C_CPU0_SA_DQS_DN<9>
J 0
(1660 4110);
DISPLAY 0.659574 (1660 4110);
PAINT MONO (1660 4110);
DISPLAY INVISIBLE (1660 4110);
FORCEPROP 1 LASTPIN (1650 4100) BN 9
J 0
(1638 4108);
DISPLAY 0.680851 (1638 4108);
PAINT GREEN (1638 4108);
FORCEPROP 2 LAST CDS_LIB standard
J 0
(1700 4100);
DISPLAY INVISIBLE (1700 4100);
FORCEPROP 1 LAST BODY_TYPE PLUMBING
J 0
(1700 4150);
DISPLAY 0.872340 (1700 4150);
PAINT GREEN (1700 4150);
DISPLAY INVISIBLE (1700 4150);
FORCEPROP 1 LAST HDL_TAP TRUE
J 0
(2025 3975);
DISPLAY 0.872340 (2025 3975);
DISPLAY INVISIBLE (2025 3975);
FORCEPROP 1 LAST PATH I168
J 0
(1698 4100);
DISPLAY 0.872340 (1698 4100);
PAINT GREEN (1698 4100);
DISPLAY INVISIBLE (1698 4100);
FORCEADD OFFPAGE..2
(2650 3075);
FORCEPROP 2 LAST $XR1 87 
J 0
(2929 3075);
DISPLAY 0.638298 (2929 3075);
PAINT MONO (2929 3075);
FORCEPROP 2 LAST $XR0 22 
J 0
(2839 3075);
DISPLAY 0.638298 (2839 3075);
PAINT MONO (2839 3075);
FORCEPROP 2 LAST CDS_LIB standard
J 0
(2650 3075);
PAINT MONO (2650 3075);
DISPLAY INVISIBLE (2650 3075);
FORCEPROP 1 LAST OFFPAGE TRUE
J 0
(2975 2950);
DISPLAY 1.170213 (2975 2950);
PAINT GREEN (2975 2950);
DISPLAY INVISIBLE (2975 2950);
FORCEPROP 1 LAST COMMENT_BODY TRUE
J 0
(2605 2980);
DISPLAY 1.170213 (2605 2980);
PAINT GREEN (2605 2980);
DISPLAY INVISIBLE (2605 2980);
FORCEPROP 2 LAST PATH I169
J 0
(2825 3150);
DISPLAY 1.021277 (2825 3150);
DISPLAY INVISIBLE (2825 3150);
FORCEADD OFFPAGE..1
(-3800 3050);
FORCEPROP 2 LAST $XR0 22 
J 0
(-4021 3050);
DISPLAY 0.638298 (-4021 3050);
PAINT MONO (-4021 3050);
FORCEPROP 2 LAST CDS_LIB standard
J 0
(-3800 3050);
PAINT MONO (-3800 3050);
DISPLAY INVISIBLE (-3800 3050);
FORCEPROP 1 LAST OFFPAGE TRUE
J 0
(-3475 2925);
DISPLAY 0.872340 (-3475 2925);
DISPLAY INVISIBLE (-3475 2925);
FORCEPROP 1 LAST COMMENT_BODY TRUE
J 0
(-3675 2950);
DISPLAY 0.872340 (-3675 2950);
PAINT GREEN (-3675 2950);
DISPLAY INVISIBLE (-3675 2950);
FORCEPROP 2 LAST PATH I17
J 0
(-3750 3125);
DISPLAY 1.021277 (-3750 3125);
DISPLAY INVISIBLE (-3750 3125);
FORCEADD OFFPAGE..2
(2650 3125);
FORCEPROP 2 LAST $XR1 87 
J 0
(2929 3125);
DISPLAY 0.638298 (2929 3125);
PAINT MONO (2929 3125);
FORCEPROP 2 LAST $XR0 22 
J 0
(2839 3125);
DISPLAY 0.638298 (2839 3125);
PAINT MONO (2839 3125);
FORCEPROP 2 LAST CDS_LIB standard
J 0
(2650 3125);
PAINT MONO (2650 3125);
DISPLAY INVISIBLE (2650 3125);
FORCEPROP 1 LAST OFFPAGE TRUE
J 0
(2975 3000);
DISPLAY 1.170213 (2975 3000);
PAINT GREEN (2975 3000);
DISPLAY INVISIBLE (2975 3000);
FORCEPROP 1 LAST COMMENT_BODY TRUE
J 0
(2605 3030);
DISPLAY 1.170213 (2605 3030);
PAINT GREEN (2605 3030);
DISPLAY INVISIBLE (2605 3030);
FORCEPROP 2 LAST PATH I170
J 0
(2825 3200);
DISPLAY 1.021277 (2825 3200);
DISPLAY INVISIBLE (2825 3200);
FORCEADD OFFPAGE..2
(2650 4125);
FORCEPROP 2 LAST $XR1 87 
J 0
(2929 4125);
DISPLAY 0.638298 (2929 4125);
PAINT MONO (2929 4125);
FORCEPROP 2 LAST $XR0 22 
J 0
(2839 4125);
DISPLAY 0.638298 (2839 4125);
PAINT MONO (2839 4125);
FORCEPROP 2 LAST CDS_LIB standard
J 0
(2650 4125);
PAINT MONO (2650 4125);
DISPLAY INVISIBLE (2650 4125);
FORCEPROP 1 LAST OFFPAGE TRUE
J 0
(2975 4000);
DISPLAY 1.170213 (2975 4000);
PAINT GREEN (2975 4000);
DISPLAY INVISIBLE (2975 4000);
FORCEPROP 1 LAST COMMENT_BODY TRUE
J 0
(2605 4030);
DISPLAY 1.170213 (2605 4030);
PAINT GREEN (2605 4030);
DISPLAY INVISIBLE (2605 4030);
FORCEPROP 2 LAST PATH I171
J 0
(2825 4200);
DISPLAY 1.021277 (2825 4200);
DISPLAY INVISIBLE (2825 4200);
FORCEADD OFFPAGE..2
(2650 4175);
FORCEPROP 2 LAST $XR1 87 
J 0
(2929 4175);
DISPLAY 0.638298 (2929 4175);
PAINT MONO (2929 4175);
FORCEPROP 2 LAST $XR0 22 
J 0
(2839 4175);
DISPLAY 0.638298 (2839 4175);
PAINT MONO (2839 4175);
FORCEPROP 2 LAST CDS_LIB standard
J 0
(2650 4175);
PAINT MONO (2650 4175);
DISPLAY INVISIBLE (2650 4175);
FORCEPROP 1 LAST OFFPAGE TRUE
J 0
(2975 4050);
DISPLAY 1.170213 (2975 4050);
PAINT GREEN (2975 4050);
DISPLAY INVISIBLE (2975 4050);
FORCEPROP 1 LAST COMMENT_BODY TRUE
J 0
(2605 4080);
DISPLAY 1.170213 (2605 4080);
PAINT GREEN (2605 4080);
DISPLAY INVISIBLE (2605 4080);
FORCEPROP 2 LAST PATH I172
J 0
(2825 4250);
DISPLAY 1.021277 (2825 4250);
DISPLAY INVISIBLE (2825 4250);
FORCEADD UNIVERSAL_GND..1
(3200 450);
FORCEPROP 3 LASTPIN (3200 500) SIG_NAME GND\g
J 0
(3210 510);
DISPLAY 0.659574 (3210 510);
PAINT MONO (3210 510);
DISPLAY INVISIBLE (3210 510);
FORCEPROP 2 LAST CDS_LIB logical_power
J 0
(3200 450);
PAINT MONO (3200 450);
DISPLAY INVISIBLE (3200 450);
FORCEPROP 1 LAST HDL_POWER GND
J 1
(3225 375);
DISPLAY 0.872340 (3225 375);
PAINT GREEN (3225 375);
DISPLAY INVISIBLE (3225 375);
FORCEPROP 1 LAST PATH I173
J 0
(3275 450);
DISPLAY 0.872340 (3275 450);
PAINT AQUA (3275 450);
DISPLAY INVISIBLE (3275 450);
FORCEADD SCONN288_ADR50017P130CC..3
(4050 2525);
FORCEPROP 1 LAST PART_NUMBER DFHST8FS461
J 0
(3595 4449);
DISPLAY 0.723404 (3595 4449);
PAINT GREEN (3595 4449);
DISPLAY INVISIBLE (3595 4449);
FORCEPROP 1 LAST MATERIAL IO
J 0
(3595 4322);
DISPLAY 0.723404 (3595 4322);
PAINT GREEN (3595 4322);
FORCEPROP 2 LAST VALUE SCONN288_ADR50017-P130CC
J 0
(3600 4550);
DISPLAY 1.021277 (3600 4550);
FORCEPROP 2 LAST PART_TYPE SMLF
J 0
(3600 4600);
DISPLAY 1.021277 (3600 4600);
FORCEPROP 1 LAST $LOCATION J5
J 0
(3600 4500);
DISPLAY 0.723404 (3600 4500);
PAINT GREEN (3600 4500);
FORCEPROP 0 LASTPIN (4650 900) $PN G1
J 0
(4660 910);
DISPLAY 0.680851 (4660 910);
PAINT MONO (4660 910);
FORCEPROP 0 LASTPIN (4650 850) $PN G2
J 0
(4660 860);
DISPLAY 0.680851 (4660 860);
PAINT MONO (4660 860);
FORCEPROP 0 LASTPIN (4650 800) $PN G3
J 0
(4660 810);
DISPLAY 0.680851 (4660 810);
PAINT MONO (4660 810);
FORCEPROP 0 LASTPIN (3450 4050) $PN 1
J 2
(3440 4060);
DISPLAY 0.680851 (3440 4060);
PAINT MONO (3440 4060);
FORCEPROP 0 LASTPIN (3450 4100) $PN 145
J 2
(3440 4110);
DISPLAY 0.680851 (3440 4110);
PAINT MONO (3440 4110);
FORCEPROP 0 LASTPIN (3450 4150) $PN 146
J 2
(3440 4160);
DISPLAY 0.680851 (3440 4160);
PAINT MONO (3440 4160);
FORCEPROP 0 LASTPIN (4650 1000) $PN 6
J 0
(4660 1010);
DISPLAY 0.680851 (4660 1010);
PAINT MONO (4660 1010);
FORCEPROP 0 LASTPIN (4650 1050) $PN 8
J 0
(4660 1060);
DISPLAY 0.680851 (4660 1060);
PAINT MONO (4660 1060);
FORCEPROP 0 LASTPIN (4650 1100) $PN 10
J 0
(4660 1110);
DISPLAY 0.680851 (4660 1110);
PAINT MONO (4660 1110);
FORCEPROP 0 LASTPIN (4650 1150) $PN 13
J 0
(4660 1160);
DISPLAY 0.680851 (4660 1160);
PAINT MONO (4660 1160);
FORCEPROP 0 LASTPIN (4650 1200) $PN 15
J 0
(4660 1210);
DISPLAY 0.680851 (4660 1210);
PAINT MONO (4660 1210);
FORCEPROP 0 LASTPIN (4650 1250) $PN 17
J 0
(4660 1260);
DISPLAY 0.680851 (4660 1260);
PAINT MONO (4660 1260);
FORCEPROP 0 LASTPIN (4650 1300) $PN 19
J 0
(4660 1310);
DISPLAY 0.680851 (4660 1310);
PAINT MONO (4660 1310);
FORCEPROP 0 LASTPIN (4650 1350) $PN 21
J 0
(4660 1360);
DISPLAY 0.680851 (4660 1360);
PAINT MONO (4660 1360);
FORCEPROP 0 LASTPIN (4650 1400) $PN 24
J 0
(4660 1410);
DISPLAY 0.680851 (4660 1410);
PAINT MONO (4660 1410);
FORCEPROP 0 LASTPIN (4650 1450) $PN 26
J 0
(4660 1460);
DISPLAY 0.680851 (4660 1460);
PAINT MONO (4660 1460);
FORCEPROP 0 LASTPIN (4650 1500) $PN 28
J 0
(4660 1510);
DISPLAY 0.680851 (4660 1510);
PAINT MONO (4660 1510);
FORCEPROP 0 LASTPIN (4650 1550) $PN 30
J 0
(4660 1560);
DISPLAY 0.680851 (4660 1560);
PAINT MONO (4660 1560);
FORCEPROP 0 LASTPIN (4650 1600) $PN 32
J 0
(4660 1610);
DISPLAY 0.680851 (4660 1610);
PAINT MONO (4660 1610);
FORCEPROP 0 LASTPIN (4650 1650) $PN 35
J 0
(4660 1660);
DISPLAY 0.680851 (4660 1660);
PAINT MONO (4660 1660);
FORCEPROP 0 LASTPIN (4650 1700) $PN 37
J 0
(4660 1710);
DISPLAY 0.680851 (4660 1710);
PAINT MONO (4660 1710);
FORCEPROP 0 LASTPIN (4650 1750) $PN 39
J 0
(4660 1760);
DISPLAY 0.680851 (4660 1760);
PAINT MONO (4660 1760);
FORCEPROP 0 LASTPIN (4650 1800) $PN 41
J 0
(4660 1810);
DISPLAY 0.680851 (4660 1810);
PAINT MONO (4660 1810);
FORCEPROP 0 LASTPIN (4650 1850) $PN 43
J 0
(4660 1860);
DISPLAY 0.680851 (4660 1860);
PAINT MONO (4660 1860);
FORCEPROP 0 LASTPIN (4650 1900) $PN 46
J 0
(4660 1910);
DISPLAY 0.680851 (4660 1910);
PAINT MONO (4660 1910);
FORCEPROP 0 LASTPIN (4650 1950) $PN 48
J 0
(4660 1960);
DISPLAY 0.680851 (4660 1960);
PAINT MONO (4660 1960);
FORCEPROP 0 LASTPIN (4650 2000) $PN 50
J 0
(4660 2010);
DISPLAY 0.680851 (4660 2010);
PAINT MONO (4660 2010);
FORCEPROP 0 LASTPIN (4650 2050) $PN 52
J 0
(4660 2060);
DISPLAY 0.680851 (4660 2060);
PAINT MONO (4660 2060);
FORCEPROP 0 LASTPIN (4650 2100) $PN 54
J 0
(4660 2110);
DISPLAY 0.680851 (4660 2110);
PAINT MONO (4660 2110);
FORCEPROP 0 LASTPIN (4650 2150) $PN 57
J 0
(4660 2160);
DISPLAY 0.680851 (4660 2160);
PAINT MONO (4660 2160);
FORCEPROP 0 LASTPIN (4650 2200) $PN 59
J 0
(4660 2210);
DISPLAY 0.680851 (4660 2210);
PAINT MONO (4660 2210);
FORCEPROP 0 LASTPIN (4650 2250) $PN 61
J 0
(4660 2260);
DISPLAY 0.680851 (4660 2260);
PAINT MONO (4660 2260);
FORCEPROP 0 LASTPIN (4650 2300) $PN 63
J 0
(4660 2310);
DISPLAY 0.680851 (4660 2310);
PAINT MONO (4660 2310);
FORCEPROP 0 LASTPIN (4650 2350) $PN 65
J 0
(4660 2360);
DISPLAY 0.680851 (4660 2360);
PAINT MONO (4660 2360);
FORCEPROP 0 LASTPIN (4650 2400) $PN 67
J 0
(4660 2410);
DISPLAY 0.680851 (4660 2410);
PAINT MONO (4660 2410);
FORCEPROP 0 LASTPIN (4650 2450) $PN 69
J 0
(4660 2460);
DISPLAY 0.680851 (4660 2460);
PAINT MONO (4660 2460);
FORCEPROP 0 LASTPIN (4650 2500) $PN 71
J 0
(4660 2510);
DISPLAY 0.680851 (4660 2510);
PAINT MONO (4660 2510);
FORCEPROP 0 LASTPIN (4650 2550) $PN 73
J 0
(4660 2560);
DISPLAY 0.680851 (4660 2560);
PAINT MONO (4660 2560);
FORCEPROP 0 LASTPIN (4650 2600) $PN 75
J 0
(4660 2610);
DISPLAY 0.680851 (4660 2610);
PAINT MONO (4660 2610);
FORCEPROP 0 LASTPIN (4650 2650) $PN 77
J 0
(4660 2660);
DISPLAY 0.680851 (4660 2660);
PAINT MONO (4660 2660);
FORCEPROP 0 LASTPIN (4650 2700) $PN 79
J 0
(4660 2710);
DISPLAY 0.680851 (4660 2710);
PAINT MONO (4660 2710);
FORCEPROP 0 LASTPIN (4650 2750) $PN 81
J 0
(4660 2760);
DISPLAY 0.680851 (4660 2760);
PAINT MONO (4660 2760);
FORCEPROP 0 LASTPIN (4650 2800) $PN 83
J 0
(4660 2810);
DISPLAY 0.680851 (4660 2810);
PAINT MONO (4660 2810);
FORCEPROP 0 LASTPIN (4650 2850) $PN 85
J 0
(4660 2860);
DISPLAY 0.680851 (4660 2860);
PAINT MONO (4660 2860);
FORCEPROP 0 LASTPIN (4650 2900) $PN 88
J 0
(4660 2910);
DISPLAY 0.680851 (4660 2910);
PAINT MONO (4660 2910);
FORCEPROP 0 LASTPIN (4650 2950) $PN 90
J 0
(4660 2960);
DISPLAY 0.680851 (4660 2960);
PAINT MONO (4660 2960);
FORCEPROP 0 LASTPIN (4650 3000) $PN 92
J 0
(4660 3010);
DISPLAY 0.680851 (4660 3010);
PAINT MONO (4660 3010);
FORCEPROP 0 LASTPIN (4650 3050) $PN 95
J 0
(4660 3060);
DISPLAY 0.680851 (4660 3060);
PAINT MONO (4660 3060);
FORCEPROP 0 LASTPIN (4650 3100) $PN 97
J 0
(4660 3110);
DISPLAY 0.680851 (4660 3110);
PAINT MONO (4660 3110);
FORCEPROP 0 LASTPIN (4650 3150) $PN 99
J 0
(4660 3160);
DISPLAY 0.680851 (4660 3160);
PAINT MONO (4660 3160);
FORCEPROP 0 LASTPIN (4650 3200) $PN 101
J 0
(4660 3210);
DISPLAY 0.680851 (4660 3210);
PAINT MONO (4660 3210);
FORCEPROP 0 LASTPIN (4650 3250) $PN 103
J 0
(4660 3260);
DISPLAY 0.680851 (4660 3260);
PAINT MONO (4660 3260);
FORCEPROP 0 LASTPIN (4650 3300) $PN 106
J 0
(4660 3310);
DISPLAY 0.680851 (4660 3310);
PAINT MONO (4660 3310);
FORCEPROP 0 LASTPIN (4650 3350) $PN 108
J 0
(4660 3360);
DISPLAY 0.680851 (4660 3360);
PAINT MONO (4660 3360);
FORCEPROP 0 LASTPIN (4650 3400) $PN 110
J 0
(4660 3410);
DISPLAY 0.680851 (4660 3410);
PAINT MONO (4660 3410);
FORCEPROP 0 LASTPIN (4650 3450) $PN 112
J 0
(4660 3460);
DISPLAY 0.680851 (4660 3460);
PAINT MONO (4660 3460);
FORCEPROP 0 LASTPIN (4650 3500) $PN 114
J 0
(4660 3510);
DISPLAY 0.680851 (4660 3510);
PAINT MONO (4660 3510);
FORCEPROP 0 LASTPIN (4650 3550) $PN 117
J 0
(4660 3560);
DISPLAY 0.680851 (4660 3560);
PAINT MONO (4660 3560);
FORCEPROP 0 LASTPIN (4650 3600) $PN 119
J 0
(4660 3610);
DISPLAY 0.680851 (4660 3610);
PAINT MONO (4660 3610);
FORCEPROP 0 LASTPIN (4650 3650) $PN 121
J 0
(4660 3660);
DISPLAY 0.680851 (4660 3660);
PAINT MONO (4660 3660);
FORCEPROP 0 LASTPIN (4650 3700) $PN 123
J 0
(4660 3710);
DISPLAY 0.680851 (4660 3710);
PAINT MONO (4660 3710);
FORCEPROP 0 LASTPIN (4650 3750) $PN 125
J 0
(4660 3760);
DISPLAY 0.680851 (4660 3760);
PAINT MONO (4660 3760);
FORCEPROP 0 LASTPIN (4650 3800) $PN 128
J 0
(4660 3810);
DISPLAY 0.680851 (4660 3810);
PAINT MONO (4660 3810);
FORCEPROP 0 LASTPIN (4650 3850) $PN 130
J 0
(4660 3860);
DISPLAY 0.680851 (4660 3860);
PAINT MONO (4660 3860);
FORCEPROP 0 LASTPIN (4650 3900) $PN 132
J 0
(4660 3910);
DISPLAY 0.680851 (4660 3910);
PAINT MONO (4660 3910);
FORCEPROP 0 LASTPIN (4650 3950) $PN 134
J 0
(4660 3960);
DISPLAY 0.680851 (4660 3960);
PAINT MONO (4660 3960);
FORCEPROP 0 LASTPIN (4650 4000) $PN 136
J 0
(4660 4010);
DISPLAY 0.680851 (4660 4010);
PAINT MONO (4660 4010);
FORCEPROP 0 LASTPIN (4650 4050) $PN 139
J 0
(4660 4060);
DISPLAY 0.680851 (4660 4060);
PAINT MONO (4660 4060);
FORCEPROP 0 LASTPIN (4650 4100) $PN 141
J 0
(4660 4110);
DISPLAY 0.680851 (4660 4110);
PAINT MONO (4660 4110);
FORCEPROP 0 LASTPIN (4650 4150) $PN 143
J 0
(4660 4160);
DISPLAY 0.680851 (4660 4160);
PAINT MONO (4660 4160);
FORCEPROP 0 LASTPIN (3450 900) $PN 151
J 2
(3440 910);
DISPLAY 0.680851 (3440 910);
PAINT MONO (3440 910);
FORCEPROP 0 LASTPIN (3450 950) $PN 153
J 2
(3440 960);
DISPLAY 0.680851 (3440 960);
PAINT MONO (3440 960);
FORCEPROP 0 LASTPIN (3450 1000) $PN 155
J 2
(3440 1010);
DISPLAY 0.680851 (3440 1010);
PAINT MONO (3440 1010);
FORCEPROP 0 LASTPIN (3450 1050) $PN 158
J 2
(3440 1060);
DISPLAY 0.680851 (3440 1060);
PAINT MONO (3440 1060);
FORCEPROP 0 LASTPIN (3450 1100) $PN 160
J 2
(3440 1110);
DISPLAY 0.680851 (3440 1110);
PAINT MONO (3440 1110);
FORCEPROP 0 LASTPIN (3450 1150) $PN 162
J 2
(3440 1160);
DISPLAY 0.680851 (3440 1160);
PAINT MONO (3440 1160);
FORCEPROP 0 LASTPIN (3450 1200) $PN 164
J 2
(3440 1210);
DISPLAY 0.680851 (3440 1210);
PAINT MONO (3440 1210);
FORCEPROP 0 LASTPIN (3450 1250) $PN 166
J 2
(3440 1260);
DISPLAY 0.680851 (3440 1260);
PAINT MONO (3440 1260);
FORCEPROP 0 LASTPIN (3450 1300) $PN 169
J 2
(3440 1310);
DISPLAY 0.680851 (3440 1310);
PAINT MONO (3440 1310);
FORCEPROP 0 LASTPIN (3450 1350) $PN 171
J 2
(3440 1360);
DISPLAY 0.680851 (3440 1360);
PAINT MONO (3440 1360);
FORCEPROP 0 LASTPIN (3450 1400) $PN 173
J 2
(3440 1410);
DISPLAY 0.680851 (3440 1410);
PAINT MONO (3440 1410);
FORCEPROP 0 LASTPIN (3450 1450) $PN 175
J 2
(3440 1460);
DISPLAY 0.680851 (3440 1460);
PAINT MONO (3440 1460);
FORCEPROP 0 LASTPIN (3450 1500) $PN 177
J 2
(3440 1510);
DISPLAY 0.680851 (3440 1510);
PAINT MONO (3440 1510);
FORCEPROP 0 LASTPIN (3450 1550) $PN 180
J 2
(3440 1560);
DISPLAY 0.680851 (3440 1560);
PAINT MONO (3440 1560);
FORCEPROP 0 LASTPIN (3450 1600) $PN 182
J 2
(3440 1610);
DISPLAY 0.680851 (3440 1610);
PAINT MONO (3440 1610);
FORCEPROP 0 LASTPIN (3450 1650) $PN 184
J 2
(3440 1660);
DISPLAY 0.680851 (3440 1660);
PAINT MONO (3440 1660);
FORCEPROP 0 LASTPIN (3450 1700) $PN 186
J 2
(3440 1710);
DISPLAY 0.680851 (3440 1710);
PAINT MONO (3440 1710);
FORCEPROP 0 LASTPIN (3450 1750) $PN 188
J 2
(3440 1760);
DISPLAY 0.680851 (3440 1760);
PAINT MONO (3440 1760);
FORCEPROP 0 LASTPIN (3450 1800) $PN 191
J 2
(3440 1810);
DISPLAY 0.680851 (3440 1810);
PAINT MONO (3440 1810);
FORCEPROP 0 LASTPIN (3450 1850) $PN 193
J 2
(3440 1860);
DISPLAY 0.680851 (3440 1860);
PAINT MONO (3440 1860);
FORCEPROP 0 LASTPIN (3450 1900) $PN 195
J 2
(3440 1910);
DISPLAY 0.680851 (3440 1910);
PAINT MONO (3440 1910);
FORCEPROP 0 LASTPIN (3450 1950) $PN 197
J 2
(3440 1960);
DISPLAY 0.680851 (3440 1960);
PAINT MONO (3440 1960);
FORCEPROP 0 LASTPIN (3450 2000) $PN 199
J 2
(3440 2010);
DISPLAY 0.680851 (3440 2010);
PAINT MONO (3440 2010);
FORCEPROP 0 LASTPIN (3450 2050) $PN 202
J 2
(3440 2060);
DISPLAY 0.680851 (3440 2060);
PAINT MONO (3440 2060);
FORCEPROP 0 LASTPIN (3450 2100) $PN 204
J 2
(3440 2110);
DISPLAY 0.680851 (3440 2110);
PAINT MONO (3440 2110);
FORCEPROP 0 LASTPIN (3450 2150) $PN 206
J 2
(3440 2160);
DISPLAY 0.680851 (3440 2160);
PAINT MONO (3440 2160);
FORCEPROP 0 LASTPIN (3450 2200) $PN 208
J 2
(3440 2210);
DISPLAY 0.680851 (3440 2210);
PAINT MONO (3440 2210);
FORCEPROP 0 LASTPIN (3450 2250) $PN 210
J 2
(3440 2260);
DISPLAY 0.680851 (3440 2260);
PAINT MONO (3440 2260);
FORCEPROP 0 LASTPIN (3450 2300) $PN 212
J 2
(3440 2310);
DISPLAY 0.680851 (3440 2310);
PAINT MONO (3440 2310);
FORCEPROP 0 LASTPIN (3450 2350) $PN 214
J 2
(3440 2360);
DISPLAY 0.680851 (3440 2360);
PAINT MONO (3440 2360);
FORCEPROP 0 LASTPIN (3450 2400) $PN 216
J 2
(3440 2410);
DISPLAY 0.680851 (3440 2410);
PAINT MONO (3440 2410);
FORCEPROP 0 LASTPIN (3450 2450) $PN 219
J 2
(3440 2460);
DISPLAY 0.680851 (3440 2460);
PAINT MONO (3440 2460);
FORCEPROP 0 LASTPIN (3450 2500) $PN 222
J 2
(3440 2510);
DISPLAY 0.680851 (3440 2510);
PAINT MONO (3440 2510);
FORCEPROP 0 LASTPIN (3450 2550) $PN 224
J 2
(3440 2560);
DISPLAY 0.680851 (3440 2560);
PAINT MONO (3440 2560);
FORCEPROP 0 LASTPIN (3450 2600) $PN 226
J 2
(3440 2610);
DISPLAY 0.680851 (3440 2610);
PAINT MONO (3440 2610);
FORCEPROP 0 LASTPIN (3450 2650) $PN 228
J 2
(3440 2660);
DISPLAY 0.680851 (3440 2660);
PAINT MONO (3440 2660);
FORCEPROP 0 LASTPIN (3450 2700) $PN 230
J 2
(3440 2710);
DISPLAY 0.680851 (3440 2710);
PAINT MONO (3440 2710);
FORCEPROP 0 LASTPIN (3450 2750) $PN 233
J 2
(3440 2760);
DISPLAY 0.680851 (3440 2760);
PAINT MONO (3440 2760);
FORCEPROP 0 LASTPIN (3450 2800) $PN 235
J 2
(3440 2810);
DISPLAY 0.680851 (3440 2810);
PAINT MONO (3440 2810);
FORCEPROP 0 LASTPIN (3450 2850) $PN 237
J 2
(3440 2860);
DISPLAY 0.680851 (3440 2860);
PAINT MONO (3440 2860);
FORCEPROP 0 LASTPIN (3450 2900) $PN 240
J 2
(3440 2910);
DISPLAY 0.680851 (3440 2910);
PAINT MONO (3440 2910);
FORCEPROP 0 LASTPIN (3450 2950) $PN 242
J 2
(3440 2960);
DISPLAY 0.680851 (3440 2960);
PAINT MONO (3440 2960);
FORCEPROP 0 LASTPIN (3450 3000) $PN 244
J 2
(3440 3010);
DISPLAY 0.680851 (3440 3010);
PAINT MONO (3440 3010);
FORCEPROP 0 LASTPIN (3450 3050) $PN 246
J 2
(3440 3060);
DISPLAY 0.680851 (3440 3060);
PAINT MONO (3440 3060);
FORCEPROP 0 LASTPIN (3450 3100) $PN 248
J 2
(3440 3110);
DISPLAY 0.680851 (3440 3110);
PAINT MONO (3440 3110);
FORCEPROP 0 LASTPIN (3450 3150) $PN 251
J 2
(3440 3160);
DISPLAY 0.680851 (3440 3160);
PAINT MONO (3440 3160);
FORCEPROP 0 LASTPIN (3450 3200) $PN 253
J 2
(3440 3210);
DISPLAY 0.680851 (3440 3210);
PAINT MONO (3440 3210);
FORCEPROP 0 LASTPIN (3450 3250) $PN 255
J 2
(3440 3260);
DISPLAY 0.680851 (3440 3260);
PAINT MONO (3440 3260);
FORCEPROP 0 LASTPIN (3450 3300) $PN 257
J 2
(3440 3310);
DISPLAY 0.680851 (3440 3310);
PAINT MONO (3440 3310);
FORCEPROP 0 LASTPIN (3450 3350) $PN 259
J 2
(3440 3360);
DISPLAY 0.680851 (3440 3360);
PAINT MONO (3440 3360);
FORCEPROP 0 LASTPIN (3450 3400) $PN 262
J 2
(3440 3410);
DISPLAY 0.680851 (3440 3410);
PAINT MONO (3440 3410);
FORCEPROP 0 LASTPIN (3450 3450) $PN 264
J 2
(3440 3460);
DISPLAY 0.680851 (3440 3460);
PAINT MONO (3440 3460);
FORCEPROP 0 LASTPIN (3450 3500) $PN 266
J 2
(3440 3510);
DISPLAY 0.680851 (3440 3510);
PAINT MONO (3440 3510);
FORCEPROP 0 LASTPIN (3450 3550) $PN 268
J 2
(3440 3560);
DISPLAY 0.680851 (3440 3560);
PAINT MONO (3440 3560);
FORCEPROP 0 LASTPIN (3450 3600) $PN 270
J 2
(3440 3610);
DISPLAY 0.680851 (3440 3610);
PAINT MONO (3440 3610);
FORCEPROP 0 LASTPIN (3450 3650) $PN 273
J 2
(3440 3660);
DISPLAY 0.680851 (3440 3660);
PAINT MONO (3440 3660);
FORCEPROP 0 LASTPIN (3450 3700) $PN 275
J 2
(3440 3710);
DISPLAY 0.680851 (3440 3710);
PAINT MONO (3440 3710);
FORCEPROP 0 LASTPIN (3450 3750) $PN 277
J 2
(3440 3760);
DISPLAY 0.680851 (3440 3760);
PAINT MONO (3440 3760);
FORCEPROP 0 LASTPIN (3450 3800) $PN 279
J 2
(3440 3810);
DISPLAY 0.680851 (3440 3810);
PAINT MONO (3440 3810);
FORCEPROP 0 LASTPIN (3450 3850) $PN 281
J 2
(3440 3860);
DISPLAY 0.680851 (3440 3860);
PAINT MONO (3440 3860);
FORCEPROP 0 LASTPIN (3450 3900) $PN 284
J 2
(3440 3910);
DISPLAY 0.680851 (3440 3910);
PAINT MONO (3440 3910);
FORCEPROP 0 LASTPIN (3450 3950) $PN 286
J 2
(3440 3960);
DISPLAY 0.680851 (3440 3960);
PAINT MONO (3440 3960);
FORCEPROP 0 LASTPIN (3450 4000) $PN 288
J 2
(3440 4010);
DISPLAY 0.680851 (3440 4010);
PAINT MONO (3440 4010);
FORCEPROP 1 LAST NEEDS_NO_SIZE TRUE
J 0
(4050 2525);
DISPLAY 0.723404 (4050 2525);
PAINT GREEN (4050 2525);
DISPLAY INVISIBLE (4050 2525);
FORCEPROP 1 LAST CDS_LMAN_SYM_OUTLINE -450,1775,450,-1775
J 0
(4050 2525);
DISPLAY 0.468085 (4050 2525);
PAINT GREEN (4050 2525);
DISPLAY INVISIBLE (4050 2525);
FORCEPROP 2 LAST CDS_LIB pure_quanta
J 0
(4050 2525);
DISPLAY INVISIBLE (4050 2525);
FORCEPROP 2 LAST CDS_LOCATION J5
J 0
(3600 4650);
DISPLAY 1.021277 (3600 4650);
DISPLAY INVISIBLE (3600 4650);
FORCEPROP 0 LAST $SEC 3
J 0
(3600 4650);
DISPLAY 0.680851 (3600 4650);
PAINT MONO (3600 4650);
DISPLAY INVISIBLE (3600 4650);
FORCEPROP 2 LAST CDS_SEC 3
J 0
(3600 4650);
DISPLAY 1.021277 (3600 4650);
DISPLAY INVISIBLE (3600 4650);
FORCEPROP 1 LAST PATH I174
J 0
(4050 2525);
DISPLAY 0.723404 (4050 2525);
PAINT GREEN (4050 2525);
DISPLAY INVISIBLE (4050 2525);
FORCEADD UNIVERSAL_GND..1
(4900 450);
FORCEPROP 3 LASTPIN (4900 500) SIG_NAME GND\g
J 0
(4910 510);
DISPLAY 0.659574 (4910 510);
PAINT MONO (4910 510);
DISPLAY INVISIBLE (4910 510);
FORCEPROP 2 LAST CDS_LIB logical_power
J 0
(4900 450);
PAINT MONO (4900 450);
DISPLAY INVISIBLE (4900 450);
FORCEPROP 1 LAST HDL_POWER GND
J 1
(4925 375);
DISPLAY 0.872340 (4925 375);
PAINT GREEN (4925 375);
DISPLAY INVISIBLE (4925 375);
FORCEPROP 1 LAST PATH I175
J 0
(4975 450);
DISPLAY 0.872340 (4975 450);
PAINT AQUA (4975 450);
DISPLAY INVISIBLE (4975 450);
FORCEADD VCC_CORE..1
(3200 4700);
FORCEPROP 3 LASTPIN (3200 4650) SIG_NAME P12V_S3_AUX_CPU0_NVDIMM\g
J 0
(3210 4660);
DISPLAY 0.659574 (3210 4660);
PAINT MONO (3210 4660);
DISPLAY INVISIBLE (3210 4660);
FORCEPROP 1 LAST HDL_POWER P12V_S3_AUX_CPU0_NVDIMM
J 1
(3200 4750);
DISPLAY 1.148936 (3200 4750);
PAINT GREEN (3200 4750);
FORCEPROP 2 LAST CDS_LIB logical_power
J 0
(3200 4700);
PAINT MONO (3200 4700);
DISPLAY INVISIBLE (3200 4700);
FORCEPROP 1 LAST PATH I176
J 0
(3250 4725);
DISPLAY 0.872340 (3250 4725);
PAINT AQUA (3250 4725);
DISPLAY INVISIBLE (3250 4725);
FORCEADD OFFPAGE..3
R 2
(-3800 1300);
FORCEPROP 2 LAST $XR0 114 
J 0
(-4080 1300);
DISPLAY 0.638298 (-4080 1300);
PAINT MONO (-4080 1300);
FORCEPROP 2 LAST CDS_LIB standard
J 0
(-3800 1300);
PAINT MONO (-3800 1300);
DISPLAY INVISIBLE (-3800 1300);
FORCEPROP 1 LAST OFFPAGE TRUE
J 2
(-4125 1175);
DISPLAY 0.872340 (-4125 1175);
DISPLAY INVISIBLE (-4125 1175);
FORCEPROP 1 LAST COMMENT_BODY TRUE
J 2
(-3750 1200);
DISPLAY 0.872340 (-3750 1200);
PAINT GREEN (-3750 1200);
DISPLAY INVISIBLE (-3750 1200);
FORCEPROP 2 LAST PATH I177
J 0
(-3750 1375);
DISPLAY 1.021277 (-3750 1375);
DISPLAY INVISIBLE (-3750 1375);
FORCEADD SCONN288_ADR50017P130CC..2
(625 3150);
FORCEPROP 1 LAST PART_NUMBER DFHST8FS461
J 0
(32 4450);
DISPLAY 0.723404 (32 4450);
PAINT GREEN (32 4450);
DISPLAY INVISIBLE (32 4450);
FORCEPROP 1 LAST MATERIAL IO
J 0
(32 4323);
DISPLAY 0.723404 (32 4323);
PAINT GREEN (32 4323);
FORCEPROP 2 LAST PART_TYPE SMLF
J 0
(50 4700);
DISPLAY 1.021277 (50 4700);
FORCEPROP 2 LAST VALUE SCONN288_ADR50017-P130CC
J 0
(50 4650);
DISPLAY 1.021277 (50 4650);
FORCEPROP 1 LAST LOCATION J5
J 0
(32 4597);
DISPLAY 0.723404 (32 4597);
PAINT GREEN (32 4597);
FORCEPROP 0 LASTPIN (1375 3200) $PN 12
J 0
(1385 3210);
DISPLAY 0.680851 (1385 3210);
PAINT MONO (1385 3210);
FORCEPROP 0 LASTPIN (1375 3250) $PN 11
J 0
(1385 3260);
DISPLAY 0.680851 (1385 3260);
PAINT MONO (1385 3260);
FORCEPROP 0 LASTPIN (1375 2150) $PN 105
J 0
(1385 2160);
DISPLAY 0.680851 (1385 2160);
PAINT MONO (1385 2160);
FORCEPROP 0 LASTPIN (1375 2200) $PN 104
J 0
(1385 2210);
DISPLAY 0.680851 (1385 2210);
PAINT MONO (1385 2210);
FORCEPROP 0 LASTPIN (1375 3300) $PN 23
J 0
(1385 3310);
DISPLAY 0.680851 (1385 3310);
PAINT MONO (1385 3310);
FORCEPROP 0 LASTPIN (1375 3350) $PN 22
J 0
(1385 3360);
DISPLAY 0.680851 (1385 3360);
PAINT MONO (1385 3360);
FORCEPROP 0 LASTPIN (1375 2250) $PN 116
J 0
(1385 2260);
DISPLAY 0.680851 (1385 2260);
PAINT MONO (1385 2260);
FORCEPROP 0 LASTPIN (1375 2300) $PN 115
J 0
(1385 2310);
DISPLAY 0.680851 (1385 2310);
PAINT MONO (1385 2310);
FORCEPROP 0 LASTPIN (1375 3400) $PN 34
J 0
(1385 3410);
DISPLAY 0.680851 (1385 3410);
PAINT MONO (1385 3410);
FORCEPROP 0 LASTPIN (1375 3450) $PN 33
J 0
(1385 3460);
DISPLAY 0.680851 (1385 3460);
PAINT MONO (1385 3460);
FORCEPROP 0 LASTPIN (1375 2350) $PN 127
J 0
(1385 2360);
DISPLAY 0.680851 (1385 2360);
PAINT MONO (1385 2360);
FORCEPROP 0 LASTPIN (1375 2400) $PN 126
J 0
(1385 2410);
DISPLAY 0.680851 (1385 2410);
PAINT MONO (1385 2410);
FORCEPROP 0 LASTPIN (1375 3500) $PN 45
J 0
(1385 3510);
DISPLAY 0.680851 (1385 3510);
PAINT MONO (1385 3510);
FORCEPROP 0 LASTPIN (1375 3550) $PN 44
J 0
(1385 3560);
DISPLAY 0.680851 (1385 3560);
PAINT MONO (1385 3560);
FORCEPROP 0 LASTPIN (1375 2450) $PN 138
J 0
(1385 2460);
DISPLAY 0.680851 (1385 2460);
PAINT MONO (1385 2460);
FORCEPROP 0 LASTPIN (1375 2500) $PN 137
J 0
(1385 2510);
DISPLAY 0.680851 (1385 2510);
PAINT MONO (1385 2510);
FORCEPROP 0 LASTPIN (1375 3600) $PN 56
J 0
(1385 3610);
DISPLAY 0.680851 (1385 3610);
PAINT MONO (1385 3610);
FORCEPROP 0 LASTPIN (1375 3650) $PN 55
J 0
(1385 3660);
DISPLAY 0.680851 (1385 3660);
PAINT MONO (1385 3660);
FORCEPROP 0 LASTPIN (1375 2550) $PN 238
J 0
(1385 2560);
DISPLAY 0.680851 (1385 2560);
PAINT MONO (1385 2560);
FORCEPROP 0 LASTPIN (1375 2600) $PN 239
J 0
(1385 2610);
DISPLAY 0.680851 (1385 2610);
PAINT MONO (1385 2610);
FORCEPROP 0 LASTPIN (1375 3700) $PN 156
J 0
(1385 3710);
DISPLAY 0.680851 (1385 3710);
PAINT MONO (1385 3710);
FORCEPROP 0 LASTPIN (1375 3750) $PN 157
J 0
(1385 3760);
DISPLAY 0.680851 (1385 3760);
PAINT MONO (1385 3760);
FORCEPROP 0 LASTPIN (1375 2650) $PN 249
J 0
(1385 2660);
DISPLAY 0.680851 (1385 2660);
PAINT MONO (1385 2660);
FORCEPROP 0 LASTPIN (1375 2700) $PN 250
J 0
(1385 2710);
DISPLAY 0.680851 (1385 2710);
PAINT MONO (1385 2710);
FORCEPROP 0 LASTPIN (1375 3800) $PN 167
J 0
(1385 3810);
DISPLAY 0.680851 (1385 3810);
PAINT MONO (1385 3810);
FORCEPROP 0 LASTPIN (1375 3850) $PN 168
J 0
(1385 3860);
DISPLAY 0.680851 (1385 3860);
PAINT MONO (1385 3860);
FORCEPROP 0 LASTPIN (1375 2750) $PN 260
J 0
(1385 2760);
DISPLAY 0.680851 (1385 2760);
PAINT MONO (1385 2760);
FORCEPROP 0 LASTPIN (1375 2800) $PN 261
J 0
(1385 2810);
DISPLAY 0.680851 (1385 2810);
PAINT MONO (1385 2810);
FORCEPROP 0 LASTPIN (1375 3900) $PN 178
J 0
(1385 3910);
DISPLAY 0.680851 (1385 3910);
PAINT MONO (1385 3910);
FORCEPROP 0 LASTPIN (1375 3950) $PN 179
J 0
(1385 3960);
DISPLAY 0.680851 (1385 3960);
PAINT MONO (1385 3960);
FORCEPROP 0 LASTPIN (1375 2850) $PN 271
J 0
(1385 2860);
DISPLAY 0.680851 (1385 2860);
PAINT MONO (1385 2860);
FORCEPROP 0 LASTPIN (1375 2900) $PN 272
J 0
(1385 2910);
DISPLAY 0.680851 (1385 2910);
PAINT MONO (1385 2910);
FORCEPROP 0 LASTPIN (1375 4000) $PN 189
J 0
(1385 4010);
DISPLAY 0.680851 (1385 4010);
PAINT MONO (1385 4010);
FORCEPROP 0 LASTPIN (1375 4050) $PN 190
J 0
(1385 4060);
DISPLAY 0.680851 (1385 4060);
PAINT MONO (1385 4060);
FORCEPROP 0 LASTPIN (1375 2950) $PN 282
J 0
(1385 2960);
DISPLAY 0.680851 (1385 2960);
PAINT MONO (1385 2960);
FORCEPROP 0 LASTPIN (1375 3000) $PN 283
J 0
(1385 3010);
DISPLAY 0.680851 (1385 3010);
PAINT MONO (1385 3010);
FORCEPROP 0 LASTPIN (1375 4100) $PN 200
J 0
(1385 4110);
DISPLAY 0.680851 (1385 4110);
PAINT MONO (1385 4110);
FORCEPROP 0 LASTPIN (1375 4150) $PN 201
J 0
(1385 4160);
DISPLAY 0.680851 (1385 4160);
PAINT MONO (1385 4160);
FORCEPROP 0 LASTPIN (1375 3050) $PN 94
J 0
(1385 3060);
DISPLAY 0.680851 (1385 3060);
PAINT MONO (1385 3060);
FORCEPROP 0 LASTPIN (1375 3100) $PN 93
J 0
(1385 3110);
DISPLAY 0.680851 (1385 3110);
PAINT MONO (1385 3110);
FORCEPROP 1 LAST NEEDS_NO_SIZE TRUE
J 0
(625 3150);
DISPLAY 0.723404 (625 3150);
PAINT GREEN (625 3150);
DISPLAY INVISIBLE (625 3150);
FORCEPROP 1 LAST CDS_LMAN_SYM_OUTLINE -600,1150,600,-1150
J 0
(625 3150);
DISPLAY 0.468085 (625 3150);
PAINT GREEN (625 3150);
DISPLAY INVISIBLE (625 3150);
FORCEPROP 2 LAST CDS_LIB pure_quanta
J 0
(625 3150);
DISPLAY INVISIBLE (625 3150);
FORCEPROP 0 LAST $SEC 2
J 0
(50 4750);
DISPLAY 0.680851 (50 4750);
PAINT MONO (50 4750);
DISPLAY INVISIBLE (50 4750);
FORCEPROP 0 LAST CDS_SEC 2
J 0
(50 4750);
DISPLAY 1.021277 (50 4750);
DISPLAY INVISIBLE (50 4750);
FORCEPROP 1 LAST PATH I178
J 0
(625 3150);
DISPLAY 0.723404 (625 3150);
PAINT GREEN (625 3150);
DISPLAY INVISIBLE (625 3150);
FORCEADD OFFPAGE..1
(-2700 1400);
FORCEPROP 2 LAST $XR7 89 
J 0
(-3612 1400);
DISPLAY 0.638298 (-3612 1400);
PAINT MONO (-3612 1400);
FORCEPROP 2 LAST $XR6 88 
J 0
(-3522 1400);
DISPLAY 0.638298 (-3522 1400);
PAINT MONO (-3522 1400);
FORCEPROP 2 LAST $XR5 87 
J 0
(-3432 1400);
DISPLAY 0.638298 (-3432 1400);
PAINT MONO (-3432 1400);
FORCEPROP 2 LAST $XR4 85 
J 0
(-3342 1400);
DISPLAY 0.638298 (-3342 1400);
PAINT MONO (-3342 1400);
FORCEPROP 2 LAST $XR3 84 
J 0
(-3252 1400);
DISPLAY 0.638298 (-3252 1400);
PAINT MONO (-3252 1400);
FORCEPROP 2 LAST $XR2 83 
J 0
(-3162 1400);
DISPLAY 0.638298 (-3162 1400);
PAINT MONO (-3162 1400);
FORCEPROP 2 LAST $XR1 82 
J 0
(-3072 1400);
DISPLAY 0.638298 (-3072 1400);
PAINT MONO (-3072 1400);
FORCEPROP 2 LAST $XR0 229 
J 0
(-2982 1400);
DISPLAY 0.638298 (-2982 1400);
PAINT MONO (-2982 1400);
FORCEPROP 2 LAST CDS_LIB standard
J 0
(-2700 1400);
PAINT MONO (-2700 1400);
DISPLAY INVISIBLE (-2700 1400);
FORCEPROP 1 LAST OFFPAGE TRUE
J 0
(-2375 1275);
DISPLAY 0.872340 (-2375 1275);
DISPLAY INVISIBLE (-2375 1275);
FORCEPROP 1 LAST COMMENT_BODY TRUE
J 0
(-2575 1300);
DISPLAY 0.872340 (-2575 1300);
PAINT GREEN (-2575 1300);
DISPLAY INVISIBLE (-2575 1300);
FORCEPROP 2 LAST PATH I179
J 2
(-3150 1450);
DISPLAY 1.021277 (-3150 1450);
DISPLAY INVISIBLE (-3150 1450);
FORCEADD OFFPAGE..1
(-3800 3150);
FORCEPROP 2 LAST $XR0 22 
J 0
(-4021 3150);
DISPLAY 0.638298 (-4021 3150);
PAINT MONO (-4021 3150);
FORCEPROP 2 LAST CDS_LIB standard
J 0
(-3800 3150);
PAINT MONO (-3800 3150);
DISPLAY INVISIBLE (-3800 3150);
FORCEPROP 1 LAST OFFPAGE TRUE
J 0
(-3475 3025);
DISPLAY 0.872340 (-3475 3025);
DISPLAY INVISIBLE (-3475 3025);
FORCEPROP 1 LAST COMMENT_BODY TRUE
J 0
(-3675 3050);
DISPLAY 0.872340 (-3675 3050);
PAINT GREEN (-3675 3050);
DISPLAY INVISIBLE (-3675 3050);
FORCEPROP 2 LAST PATH I18
J 0
(-3750 3225);
DISPLAY 1.021277 (-3750 3225);
DISPLAY INVISIBLE (-3750 3225);
FORCEADD Q_RES..1
(-3925 1450);
FORCEPROP 1 LAST PART_NUMBER CS04992FB07
J 0
(-3825 1425);
DISPLAY 0.404255 (-3825 1425);
DISPLAY INVISIBLE (-3825 1425);
FORCEPROP 1 LAST VALUE 49.9
J 2
(-3700 1450);
DISPLAY 0.510638 (-3700 1450);
FORCEPROP 1 LAST MATERIAL CHIP
J 0
(-3825 1400);
DISPLAY 0.404255 (-3825 1400);
FORCEPROP 1 LAST $LOCATION R3879
J 0
(-4150 1450);
DISPLAY 0.638298 (-4150 1450);
FORCEPROP 1 LASTPIN (-4025 1450) $PN 1
J 0
(-4013 1462);
DISPLAY 0.787234 (-4013 1462);
PAINT MONO (-4013 1462);
FORCEPROP 1 LASTPIN (-3825 1450) $PN 2
J 0
(-3863 1462);
DISPLAY 0.787234 (-3863 1462);
PAINT MONO (-3863 1462);
FORCEPROP 2 LAST CDS_LIB pure_quanta
J 0
(-3925 1450);
DISPLAY INVISIBLE (-3925 1450);
FORCEPROP 1 LAST PACK_TYPE 0402LF
J 0
(-3625 1450);
DISPLAY 0.510638 (-3625 1450);
DISPLAY INVISIBLE (-3625 1450);
FORCEPROP 1 LAST TOLERANCE 1%
J 0
(-3700 1450);
DISPLAY 0.510638 (-3700 1450);
DISPLAY INVISIBLE (-3700 1450);
FORCEPROP 1 LAST WATTAGE 1/16W
J 2
(-3625 1400);
DISPLAY 0.404255 (-3625 1400);
DISPLAY INVISIBLE (-3625 1400);
FORCEPROP 0 LAST CDS_LOCATION R3879
J 0
(-4050 1500);
DISPLAY 1.021277 (-4050 1500);
DISPLAY INVISIBLE (-4050 1500);
FORCEPROP 0 LAST $SEC 1
J 0
(-4050 1500);
DISPLAY 0.680851 (-4050 1500);
PAINT MONO (-4050 1500);
DISPLAY INVISIBLE (-4050 1500);
FORCEPROP 0 LAST CDS_SEC 1
J 0
(-4050 1500);
DISPLAY 1.021277 (-4050 1500);
DISPLAY INVISIBLE (-4050 1500);
FORCEPROP 1 LAST PATH I180
J 0
(-3975 1600);
DISPLAY 0.978723 (-3975 1600);
PAINT WHITE (-3975 1600);
DISPLAY INVISIBLE (-3975 1600);
FORCEADD OFFPAGE..1
(-3800 3200);
FORCEPROP 2 LAST $XR0 22 
J 0
(-4021 3200);
DISPLAY 0.638298 (-4021 3200);
PAINT MONO (-4021 3200);
FORCEPROP 2 LAST CDS_LIB standard
J 0
(-3800 3200);
PAINT MONO (-3800 3200);
DISPLAY INVISIBLE (-3800 3200);
FORCEPROP 1 LAST OFFPAGE TRUE
J 0
(-3475 3075);
DISPLAY 0.872340 (-3475 3075);
DISPLAY INVISIBLE (-3475 3075);
FORCEPROP 1 LAST COMMENT_BODY TRUE
J 0
(-3675 3100);
DISPLAY 0.872340 (-3675 3100);
PAINT GREEN (-3675 3100);
DISPLAY INVISIBLE (-3675 3100);
FORCEPROP 2 LAST PATH I19
J 0
(-3750 3275);
DISPLAY 1.021277 (-3750 3275);
DISPLAY INVISIBLE (-3750 3275);
FORCEADD UNIVERSAL_GND..1
(-2650 -225);
FORCEPROP 3 LASTPIN (-2650 -175) SIG_NAME GND\g
J 0
(-2640 -165);
DISPLAY 0.659574 (-2640 -165);
PAINT MONO (-2640 -165);
DISPLAY INVISIBLE (-2640 -165);
FORCEPROP 2 LAST CDS_LIB logical_power
J 0
(-2650 -225);
PAINT MONO (-2650 -225);
DISPLAY INVISIBLE (-2650 -225);
FORCEPROP 1 LAST HDL_POWER GND
J 1
(-2625 -300);
DISPLAY 0.872340 (-2625 -300);
PAINT GREEN (-2625 -300);
DISPLAY INVISIBLE (-2625 -300);
FORCEPROP 1 LAST PATH I2
J 0
(-2575 -225);
DISPLAY 0.872340 (-2575 -225);
PAINT AQUA (-2575 -225);
DISPLAY INVISIBLE (-2575 -225);
FORCEADD OFFPAGE..1
(-3800 3300);
FORCEPROP 2 LAST $XR1 87 
J 0
(-4111 3300);
DISPLAY 0.638298 (-4111 3300);
PAINT MONO (-4111 3300);
FORCEPROP 2 LAST $XR0 22 
J 0
(-4021 3300);
DISPLAY 0.638298 (-4021 3300);
PAINT MONO (-4021 3300);
FORCEPROP 2 LAST CDS_LIB standard
J 0
(-3800 3300);
PAINT MONO (-3800 3300);
DISPLAY INVISIBLE (-3800 3300);
FORCEPROP 1 LAST OFFPAGE TRUE
J 0
(-3475 3175);
DISPLAY 0.872340 (-3475 3175);
DISPLAY INVISIBLE (-3475 3175);
FORCEPROP 1 LAST COMMENT_BODY TRUE
J 0
(-3675 3200);
DISPLAY 0.872340 (-3675 3200);
PAINT GREEN (-3675 3200);
DISPLAY INVISIBLE (-3675 3200);
FORCEPROP 2 LAST PATH I20
J 0
(-3750 3375);
DISPLAY 1.021277 (-3750 3375);
DISPLAY INVISIBLE (-3750 3375);
FORCEADD OFFPAGE..1
(-3800 3350);
FORCEPROP 2 LAST $XR1 87 
J 0
(-4111 3350);
DISPLAY 0.638298 (-4111 3350);
PAINT MONO (-4111 3350);
FORCEPROP 2 LAST $XR0 22 
J 0
(-4021 3350);
DISPLAY 0.638298 (-4021 3350);
PAINT MONO (-4021 3350);
FORCEPROP 2 LAST CDS_LIB standard
J 0
(-3800 3350);
PAINT MONO (-3800 3350);
DISPLAY INVISIBLE (-3800 3350);
FORCEPROP 1 LAST OFFPAGE TRUE
J 0
(-3475 3225);
DISPLAY 0.872340 (-3475 3225);
DISPLAY INVISIBLE (-3475 3225);
FORCEPROP 1 LAST COMMENT_BODY TRUE
J 0
(-3675 3250);
DISPLAY 0.872340 (-3675 3250);
PAINT GREEN (-3675 3250);
DISPLAY INVISIBLE (-3675 3250);
FORCEPROP 2 LAST PATH I21
J 0
(-3750 3425);
DISPLAY 1.021277 (-3750 3425);
DISPLAY INVISIBLE (-3750 3425);
FORCEADD OFFPAGE..1
(-3800 3775);
FORCEPROP 2 LAST $XR1 87 
J 0
(-4111 3775);
DISPLAY 0.638298 (-4111 3775);
PAINT MONO (-4111 3775);
FORCEPROP 2 LAST $XR0 22 
J 0
(-4021 3775);
DISPLAY 0.638298 (-4021 3775);
PAINT MONO (-4021 3775);
FORCEPROP 2 LAST CDS_LIB standard
J 0
(-3800 3775);
PAINT MONO (-3800 3775);
DISPLAY INVISIBLE (-3800 3775);
FORCEPROP 1 LAST OFFPAGE TRUE
J 0
(-3475 3650);
DISPLAY 0.872340 (-3475 3650);
DISPLAY INVISIBLE (-3475 3650);
FORCEPROP 1 LAST COMMENT_BODY TRUE
J 0
(-3675 3675);
DISPLAY 0.872340 (-3675 3675);
PAINT GREEN (-3675 3675);
DISPLAY INVISIBLE (-3675 3675);
FORCEPROP 2 LAST PATH I22
J 0
(-3750 3850);
DISPLAY 1.021277 (-3750 3850);
DISPLAY INVISIBLE (-3750 3850);
FORCEADD OFFPAGE..1
(-3800 4175);
FORCEPROP 2 LAST $XR1 87 
J 0
(-4111 4175);
DISPLAY 0.638298 (-4111 4175);
PAINT MONO (-4111 4175);
FORCEPROP 2 LAST $XR0 22 
J 0
(-4021 4175);
DISPLAY 0.638298 (-4021 4175);
PAINT MONO (-4021 4175);
FORCEPROP 2 LAST CDS_LIB standard
J 0
(-3800 4175);
PAINT MONO (-3800 4175);
DISPLAY INVISIBLE (-3800 4175);
FORCEPROP 1 LAST OFFPAGE TRUE
J 0
(-3475 4050);
DISPLAY 0.872340 (-3475 4050);
DISPLAY INVISIBLE (-3475 4050);
FORCEPROP 1 LAST COMMENT_BODY TRUE
J 0
(-3675 4075);
DISPLAY 0.872340 (-3675 4075);
PAINT GREEN (-3675 4075);
DISPLAY INVISIBLE (-3675 4075);
FORCEPROP 2 LAST PATH I23
J 0
(-3750 4250);
DISPLAY 1.021277 (-3750 4250);
DISPLAY INVISIBLE (-3750 4250);
FORCEADD SCONN288_ADR50017P130CC..1
(-2050 2425);
FORCEPROP 1 LAST PART_NUMBER DFHST8FS461
J 0
(-2495 4447);
DISPLAY 0.723404 (-2495 4447);
PAINT GREEN (-2495 4447);
DISPLAY INVISIBLE (-2495 4447);
FORCEPROP 1 LAST MATERIAL IO
J 0
(-2495 4320);
DISPLAY 0.723404 (-2495 4320);
PAINT GREEN (-2495 4320);
FORCEPROP 2 LAST VALUE SCONN288_ADR50017-P130CC
J 0
(-2500 4550);
DISPLAY 1.021277 (-2500 4550);
FORCEPROP 2 LAST PART_TYPE SMLF
J 0
(-2500 4600);
DISPLAY 1.021277 (-2500 4600);
FORCEPROP 1 LAST $LOCATION J5
J 0
(-2500 4500);
DISPLAY 0.723404 (-2500 4500);
PAINT GREEN (-2500 4500);
FORCEPROP 0 LASTPIN (-2650 1800) $PN 62
J 2
(-2660 1810);
DISPLAY 0.680851 (-2660 1810);
PAINT MONO (-2660 1810);
FORCEPROP 0 LASTPIN (-2650 3850) $PN 66
J 2
(-2660 3860);
DISPLAY 0.680851 (-2660 3860);
PAINT MONO (-2660 3860);
FORCEPROP 0 LASTPIN (-2650 3450) $PN 76
J 2
(-2660 3460);
DISPLAY 0.680851 (-2660 3460);
PAINT MONO (-2660 3460);
FORCEPROP 0 LASTPIN (-2650 3900) $PN 211
J 2
(-2660 3910);
DISPLAY 0.680851 (-2660 3910);
PAINT MONO (-2660 3910);
FORCEPROP 0 LASTPIN (-2650 3500) $PN 221
J 2
(-2660 3510);
DISPLAY 0.680851 (-2660 3510);
PAINT MONO (-2660 3510);
FORCEPROP 0 LASTPIN (-2650 3950) $PN 68
J 2
(-2660 3960);
DISPLAY 0.680851 (-2660 3960);
PAINT MONO (-2660 3960);
FORCEPROP 0 LASTPIN (-2650 3550) $PN 78
J 2
(-2660 3560);
DISPLAY 0.680851 (-2660 3560);
PAINT MONO (-2660 3560);
FORCEPROP 0 LASTPIN (-2650 4000) $PN 213
J 2
(-2660 4010);
DISPLAY 0.680851 (-2660 4010);
PAINT MONO (-2660 4010);
FORCEPROP 0 LASTPIN (-2650 3600) $PN 223
J 2
(-2660 3610);
DISPLAY 0.680851 (-2660 3610);
PAINT MONO (-2660 3610);
FORCEPROP 0 LASTPIN (-2650 4050) $PN 70
J 2
(-2660 4060);
DISPLAY 0.680851 (-2660 4060);
PAINT MONO (-2660 4060);
FORCEPROP 0 LASTPIN (-2650 3650) $PN 80
J 2
(-2660 3660);
DISPLAY 0.680851 (-2660 3660);
PAINT MONO (-2660 3660);
FORCEPROP 0 LASTPIN (-2650 4100) $PN 215
J 2
(-2660 4110);
DISPLAY 0.680851 (-2660 4110);
PAINT MONO (-2660 4110);
FORCEPROP 0 LASTPIN (-2650 3700) $PN 225
J 2
(-2660 3710);
DISPLAY 0.680851 (-2660 3710);
PAINT MONO (-2660 3710);
FORCEPROP 0 LASTPIN (-2650 4150) $PN 72
J 2
(-2660 4160);
DISPLAY 0.680851 (-2660 4160);
PAINT MONO (-2660 4160);
FORCEPROP 0 LASTPIN (-2650 3750) $PN 82
J 2
(-2660 3760);
DISPLAY 0.680851 (-2660 3760);
PAINT MONO (-2660 3760);
FORCEPROP 0 LASTPIN (-2650 2400) $PN 51
J 2
(-2660 2410);
DISPLAY 0.680851 (-2660 2410);
PAINT MONO (-2660 2410);
FORCEPROP 0 LASTPIN (-2650 1950) $PN 96
J 2
(-2660 1960);
DISPLAY 0.680851 (-2660 1960);
PAINT MONO (-2660 1960);
FORCEPROP 0 LASTPIN (-2650 2450) $PN 53
J 2
(-2660 2460);
DISPLAY 0.680851 (-2660 2460);
PAINT MONO (-2660 2460);
FORCEPROP 0 LASTPIN (-2650 2000) $PN 98
J 2
(-2660 2010);
DISPLAY 0.680851 (-2660 2010);
PAINT MONO (-2660 2010);
FORCEPROP 0 LASTPIN (-2650 2500) $PN 196
J 2
(-2660 2510);
DISPLAY 0.680851 (-2660 2510);
PAINT MONO (-2660 2510);
FORCEPROP 0 LASTPIN (-2650 2050) $PN 241
J 2
(-2660 2060);
DISPLAY 0.680851 (-2660 2060);
PAINT MONO (-2660 2060);
FORCEPROP 0 LASTPIN (-2650 2550) $PN 198
J 2
(-2660 2560);
DISPLAY 0.680851 (-2660 2560);
PAINT MONO (-2660 2560);
FORCEPROP 0 LASTPIN (-2650 2100) $PN 243
J 2
(-2660 2110);
DISPLAY 0.680851 (-2660 2110);
PAINT MONO (-2660 2110);
FORCEPROP 0 LASTPIN (-2650 2600) $PN 58
J 2
(-2660 2610);
DISPLAY 0.680851 (-2660 2610);
PAINT MONO (-2660 2610);
FORCEPROP 0 LASTPIN (-2650 2150) $PN 89
J 2
(-2660 2160);
DISPLAY 0.680851 (-2660 2160);
PAINT MONO (-2660 2160);
FORCEPROP 0 LASTPIN (-2650 2650) $PN 60
J 2
(-2660 2660);
DISPLAY 0.680851 (-2660 2660);
PAINT MONO (-2660 2660);
FORCEPROP 0 LASTPIN (-2650 2200) $PN 91
J 2
(-2660 2210);
DISPLAY 0.680851 (-2660 2210);
PAINT MONO (-2660 2210);
FORCEPROP 0 LASTPIN (-2650 2700) $PN 203
J 2
(-2660 2710);
DISPLAY 0.680851 (-2660 2710);
PAINT MONO (-2660 2710);
FORCEPROP 0 LASTPIN (-2650 2250) $PN 234
J 2
(-2660 2260);
DISPLAY 0.680851 (-2660 2260);
PAINT MONO (-2660 2260);
FORCEPROP 0 LASTPIN (-2650 2750) $PN 205
J 2
(-2660 2760);
DISPLAY 0.680851 (-2660 2760);
PAINT MONO (-2660 2760);
FORCEPROP 0 LASTPIN (-2650 2300) $PN 236
J 2
(-2660 2310);
DISPLAY 0.680851 (-2660 2310);
PAINT MONO (-2660 2310);
FORCEPROP 0 LASTPIN (-2650 2850) $PN 218
J 2
(-2660 2860);
DISPLAY 0.680851 (-2660 2860);
PAINT MONO (-2660 2860);
FORCEPROP 0 LASTPIN (-2650 2900) $PN 217
J 2
(-2660 2910);
DISPLAY 0.680851 (-2660 2910);
PAINT MONO (-2660 2910);
FORCEPROP 0 LASTPIN (-2650 3150) $PN 64
J 2
(-2660 3160);
DISPLAY 0.680851 (-2660 3160);
PAINT MONO (-2660 3160);
FORCEPROP 0 LASTPIN (-2650 3000) $PN 84
J 2
(-2660 3010);
DISPLAY 0.680851 (-2660 3010);
PAINT MONO (-2660 3010);
FORCEPROP 0 LASTPIN (-2650 3200) $PN 209
J 2
(-2660 3210);
DISPLAY 0.680851 (-2660 3210);
PAINT MONO (-2660 3210);
FORCEPROP 0 LASTPIN (-2650 3050) $PN 229
J 2
(-2660 3060);
DISPLAY 0.680851 (-2660 3060);
PAINT MONO (-2660 3060);
FORCEPROP 0 LASTPIN (-1450 2600) $PN 7
J 0
(-1440 2610);
DISPLAY 0.680851 (-1440 2610);
PAINT MONO (-1440 2610);
FORCEPROP 0 LASTPIN (-1450 950) $PN 100
J 0
(-1440 960);
DISPLAY 0.680851 (-1440 960);
PAINT MONO (-1440 960);
FORCEPROP 0 LASTPIN (-1450 2650) $PN 9
J 0
(-1440 2660);
DISPLAY 0.680851 (-1440 2660);
PAINT MONO (-1440 2660);
FORCEPROP 0 LASTPIN (-1450 1000) $PN 102
J 0
(-1440 1010);
DISPLAY 0.680851 (-1440 1010);
PAINT MONO (-1440 1010);
FORCEPROP 0 LASTPIN (-1450 2700) $PN 152
J 0
(-1440 2710);
DISPLAY 0.680851 (-1440 2710);
PAINT MONO (-1440 2710);
FORCEPROP 0 LASTPIN (-1450 1050) $PN 245
J 0
(-1440 1060);
DISPLAY 0.680851 (-1440 1060);
PAINT MONO (-1440 1060);
FORCEPROP 0 LASTPIN (-1450 2750) $PN 154
J 0
(-1440 2760);
DISPLAY 0.680851 (-1440 2760);
PAINT MONO (-1440 2760);
FORCEPROP 0 LASTPIN (-1450 1100) $PN 247
J 0
(-1440 1110);
DISPLAY 0.680851 (-1440 1110);
PAINT MONO (-1440 1110);
FORCEPROP 0 LASTPIN (-1450 2800) $PN 14
J 0
(-1440 2810);
DISPLAY 0.680851 (-1440 2810);
PAINT MONO (-1440 2810);
FORCEPROP 0 LASTPIN (-1450 1150) $PN 107
J 0
(-1440 1160);
DISPLAY 0.680851 (-1440 1160);
PAINT MONO (-1440 1160);
FORCEPROP 0 LASTPIN (-1450 2850) $PN 16
J 0
(-1440 2860);
DISPLAY 0.680851 (-1440 2860);
PAINT MONO (-1440 2860);
FORCEPROP 0 LASTPIN (-1450 1200) $PN 109
J 0
(-1440 1210);
DISPLAY 0.680851 (-1440 1210);
PAINT MONO (-1440 1210);
FORCEPROP 0 LASTPIN (-1450 2900) $PN 159
J 0
(-1440 2910);
DISPLAY 0.680851 (-1440 2910);
PAINT MONO (-1440 2910);
FORCEPROP 0 LASTPIN (-1450 1250) $PN 252
J 0
(-1440 1260);
DISPLAY 0.680851 (-1440 1260);
PAINT MONO (-1440 1260);
FORCEPROP 0 LASTPIN (-1450 2950) $PN 161
J 0
(-1440 2960);
DISPLAY 0.680851 (-1440 2960);
PAINT MONO (-1440 2960);
FORCEPROP 0 LASTPIN (-1450 1300) $PN 254
J 0
(-1440 1310);
DISPLAY 0.680851 (-1440 1310);
PAINT MONO (-1440 1310);
FORCEPROP 0 LASTPIN (-1450 3000) $PN 18
J 0
(-1440 3010);
DISPLAY 0.680851 (-1440 3010);
PAINT MONO (-1440 3010);
FORCEPROP 0 LASTPIN (-1450 1350) $PN 111
J 0
(-1440 1360);
DISPLAY 0.680851 (-1440 1360);
PAINT MONO (-1440 1360);
FORCEPROP 0 LASTPIN (-1450 3050) $PN 20
J 0
(-1440 3060);
DISPLAY 0.680851 (-1440 3060);
PAINT MONO (-1440 3060);
FORCEPROP 0 LASTPIN (-1450 1400) $PN 113
J 0
(-1440 1410);
DISPLAY 0.680851 (-1440 1410);
PAINT MONO (-1440 1410);
FORCEPROP 0 LASTPIN (-1450 3100) $PN 163
J 0
(-1440 3110);
DISPLAY 0.680851 (-1440 3110);
PAINT MONO (-1440 3110);
FORCEPROP 0 LASTPIN (-1450 1450) $PN 256
J 0
(-1440 1460);
DISPLAY 0.680851 (-1440 1460);
PAINT MONO (-1440 1460);
FORCEPROP 0 LASTPIN (-1450 3150) $PN 165
J 0
(-1440 3160);
DISPLAY 0.680851 (-1440 3160);
PAINT MONO (-1440 3160);
FORCEPROP 0 LASTPIN (-1450 1500) $PN 258
J 0
(-1440 1510);
DISPLAY 0.680851 (-1440 1510);
PAINT MONO (-1440 1510);
FORCEPROP 0 LASTPIN (-1450 3200) $PN 25
J 0
(-1440 3210);
DISPLAY 0.680851 (-1440 3210);
PAINT MONO (-1440 3210);
FORCEPROP 0 LASTPIN (-1450 1550) $PN 118
J 0
(-1440 1560);
DISPLAY 0.680851 (-1440 1560);
PAINT MONO (-1440 1560);
FORCEPROP 0 LASTPIN (-1450 3250) $PN 27
J 0
(-1440 3260);
DISPLAY 0.680851 (-1440 3260);
PAINT MONO (-1440 3260);
FORCEPROP 0 LASTPIN (-1450 1600) $PN 120
J 0
(-1440 1610);
DISPLAY 0.680851 (-1440 1610);
PAINT MONO (-1440 1610);
FORCEPROP 0 LASTPIN (-1450 3300) $PN 170
J 0
(-1440 3310);
DISPLAY 0.680851 (-1440 3310);
PAINT MONO (-1440 3310);
FORCEPROP 0 LASTPIN (-1450 1650) $PN 263
J 0
(-1440 1660);
DISPLAY 0.680851 (-1440 1660);
PAINT MONO (-1440 1660);
FORCEPROP 0 LASTPIN (-1450 3350) $PN 172
J 0
(-1440 3360);
DISPLAY 0.680851 (-1440 3360);
PAINT MONO (-1440 3360);
FORCEPROP 0 LASTPIN (-1450 1700) $PN 265
J 0
(-1440 1710);
DISPLAY 0.680851 (-1440 1710);
PAINT MONO (-1440 1710);
FORCEPROP 0 LASTPIN (-1450 3400) $PN 29
J 0
(-1440 3410);
DISPLAY 0.680851 (-1440 3410);
PAINT MONO (-1440 3410);
FORCEPROP 0 LASTPIN (-1450 1750) $PN 122
J 0
(-1440 1760);
DISPLAY 0.680851 (-1440 1760);
PAINT MONO (-1440 1760);
FORCEPROP 0 LASTPIN (-1450 3450) $PN 31
J 0
(-1440 3460);
DISPLAY 0.680851 (-1440 3460);
PAINT MONO (-1440 3460);
FORCEPROP 0 LASTPIN (-1450 1800) $PN 124
J 0
(-1440 1810);
DISPLAY 0.680851 (-1440 1810);
PAINT MONO (-1440 1810);
FORCEPROP 0 LASTPIN (-1450 3500) $PN 174
J 0
(-1440 3510);
DISPLAY 0.680851 (-1440 3510);
PAINT MONO (-1440 3510);
FORCEPROP 0 LASTPIN (-1450 1850) $PN 267
J 0
(-1440 1860);
DISPLAY 0.680851 (-1440 1860);
PAINT MONO (-1440 1860);
FORCEPROP 0 LASTPIN (-1450 3550) $PN 176
J 0
(-1440 3560);
DISPLAY 0.680851 (-1440 3560);
PAINT MONO (-1440 3560);
FORCEPROP 0 LASTPIN (-1450 1900) $PN 269
J 0
(-1440 1910);
DISPLAY 0.680851 (-1440 1910);
PAINT MONO (-1440 1910);
FORCEPROP 0 LASTPIN (-1450 3600) $PN 36
J 0
(-1440 3610);
DISPLAY 0.680851 (-1440 3610);
PAINT MONO (-1440 3610);
FORCEPROP 0 LASTPIN (-1450 1950) $PN 129
J 0
(-1440 1960);
DISPLAY 0.680851 (-1440 1960);
PAINT MONO (-1440 1960);
FORCEPROP 0 LASTPIN (-1450 3650) $PN 38
J 0
(-1440 3660);
DISPLAY 0.680851 (-1440 3660);
PAINT MONO (-1440 3660);
FORCEPROP 0 LASTPIN (-1450 2000) $PN 131
J 0
(-1440 2010);
DISPLAY 0.680851 (-1440 2010);
PAINT MONO (-1440 2010);
FORCEPROP 0 LASTPIN (-1450 3700) $PN 181
J 0
(-1440 3710);
DISPLAY 0.680851 (-1440 3710);
PAINT MONO (-1440 3710);
FORCEPROP 0 LASTPIN (-1450 2050) $PN 274
J 0
(-1440 2060);
DISPLAY 0.680851 (-1440 2060);
PAINT MONO (-1440 2060);
FORCEPROP 0 LASTPIN (-1450 3750) $PN 183
J 0
(-1440 3760);
DISPLAY 0.680851 (-1440 3760);
PAINT MONO (-1440 3760);
FORCEPROP 0 LASTPIN (-1450 2100) $PN 276
J 0
(-1440 2110);
DISPLAY 0.680851 (-1440 2110);
PAINT MONO (-1440 2110);
FORCEPROP 0 LASTPIN (-1450 3800) $PN 40
J 0
(-1440 3810);
DISPLAY 0.680851 (-1440 3810);
PAINT MONO (-1440 3810);
FORCEPROP 0 LASTPIN (-1450 2150) $PN 133
J 0
(-1440 2160);
DISPLAY 0.680851 (-1440 2160);
PAINT MONO (-1440 2160);
FORCEPROP 0 LASTPIN (-1450 3850) $PN 42
J 0
(-1440 3860);
DISPLAY 0.680851 (-1440 3860);
PAINT MONO (-1440 3860);
FORCEPROP 0 LASTPIN (-1450 2200) $PN 135
J 0
(-1440 2210);
DISPLAY 0.680851 (-1440 2210);
PAINT MONO (-1440 2210);
FORCEPROP 0 LASTPIN (-1450 3900) $PN 185
J 0
(-1440 3910);
DISPLAY 0.680851 (-1440 3910);
PAINT MONO (-1440 3910);
FORCEPROP 0 LASTPIN (-1450 2250) $PN 278
J 0
(-1440 2260);
DISPLAY 0.680851 (-1440 2260);
PAINT MONO (-1440 2260);
FORCEPROP 0 LASTPIN (-1450 3950) $PN 187
J 0
(-1440 3960);
DISPLAY 0.680851 (-1440 3960);
PAINT MONO (-1440 3960);
FORCEPROP 0 LASTPIN (-1450 2300) $PN 280
J 0
(-1440 2310);
DISPLAY 0.680851 (-1440 2310);
PAINT MONO (-1440 2310);
FORCEPROP 0 LASTPIN (-1450 4000) $PN 47
J 0
(-1440 4010);
DISPLAY 0.680851 (-1440 4010);
PAINT MONO (-1440 4010);
FORCEPROP 0 LASTPIN (-1450 2350) $PN 140
J 0
(-1440 2360);
DISPLAY 0.680851 (-1440 2360);
PAINT MONO (-1440 2360);
FORCEPROP 0 LASTPIN (-1450 4050) $PN 49
J 0
(-1440 4060);
DISPLAY 0.680851 (-1440 4060);
PAINT MONO (-1440 4060);
FORCEPROP 0 LASTPIN (-1450 2400) $PN 142
J 0
(-1440 2410);
DISPLAY 0.680851 (-1440 2410);
PAINT MONO (-1440 2410);
FORCEPROP 0 LASTPIN (-1450 4100) $PN 192
J 0
(-1440 4110);
DISPLAY 0.680851 (-1440 4110);
PAINT MONO (-1440 4110);
FORCEPROP 0 LASTPIN (-1450 2450) $PN 285
J 0
(-1440 2460);
DISPLAY 0.680851 (-1440 2460);
PAINT MONO (-1440 2460);
FORCEPROP 0 LASTPIN (-1450 4150) $PN 194
J 0
(-1440 4160);
DISPLAY 0.680851 (-1440 4160);
PAINT MONO (-1440 4160);
FORCEPROP 0 LASTPIN (-1450 2500) $PN 287
J 0
(-1440 2510);
DISPLAY 0.680851 (-1440 2510);
PAINT MONO (-1440 2510);
FORCEPROP 0 LASTPIN (-2650 1650) $PN 148
J 2
(-2660 1660);
DISPLAY 0.680851 (-2660 1660);
PAINT MONO (-2660 1660);
FORCEPROP 0 LASTPIN (-2650 1550) $PN 4
J 2
(-2660 1560);
DISPLAY 0.680851 (-2660 1560);
PAINT MONO (-2660 1560);
FORCEPROP 0 LASTPIN (-2650 1600) $PN 5
J 2
(-2660 1610);
DISPLAY 0.680851 (-2660 1610);
PAINT MONO (-2660 1610);
FORCEPROP 0 LASTPIN (-2650 750) $PN 86
J 2
(-2660 760);
DISPLAY 0.680851 (-2660 760);
PAINT MONO (-2660 760);
FORCEPROP 0 LASTPIN (-2650 700) $PN 87
J 2
(-2660 710);
DISPLAY 0.680851 (-2660 710);
PAINT MONO (-2660 710);
FORCEPROP 0 LASTPIN (-2650 3350) $PN 74
J 2
(-2660 3360);
DISPLAY 0.680851 (-2660 3360);
PAINT MONO (-2660 3360);
FORCEPROP 0 LASTPIN (-2650 3300) $PN 227
J 2
(-2660 3310);
DISPLAY 0.680851 (-2660 3310);
PAINT MONO (-2660 3310);
FORCEPROP 0 LASTPIN (-2650 1300) $PN 147
J 2
(-2660 1310);
DISPLAY 0.680851 (-2660 1310);
PAINT MONO (-2660 1310);
FORCEPROP 0 LASTPIN (-2650 1850) $PN 207
J 2
(-2660 1860);
DISPLAY 0.680851 (-2660 1860);
PAINT MONO (-2660 1860);
FORCEPROP 0 LASTPIN (-2650 900) $PN 2
J 2
(-2660 910);
DISPLAY 0.680851 (-2660 910);
PAINT MONO (-2660 910);
FORCEPROP 0 LASTPIN (-2650 950) $PN 144
J 2
(-2660 960);
DISPLAY 0.680851 (-2660 960);
PAINT MONO (-2660 960);
FORCEPROP 0 LASTPIN (-2650 1000) $PN 149
J 2
(-2660 1010);
DISPLAY 0.680851 (-2660 1010);
PAINT MONO (-2660 1010);
FORCEPROP 0 LASTPIN (-2650 1050) $PN 150
J 2
(-2660 1060);
DISPLAY 0.680851 (-2660 1060);
PAINT MONO (-2660 1060);
FORCEPROP 0 LASTPIN (-2650 1100) $PN 220
J 2
(-2660 1110);
DISPLAY 0.680851 (-2660 1110);
PAINT MONO (-2660 1110);
FORCEPROP 0 LASTPIN (-2650 1150) $PN 231
J 2
(-2660 1160);
DISPLAY 0.680851 (-2660 1160);
PAINT MONO (-2660 1160);
FORCEPROP 0 LASTPIN (-2650 1200) $PN 232
J 2
(-2660 1210);
DISPLAY 0.680851 (-2660 1210);
PAINT MONO (-2660 1210);
FORCEPROP 0 LASTPIN (-2650 1700) $PN 3
J 2
(-2660 1710);
DISPLAY 0.680851 (-2660 1710);
PAINT MONO (-2660 1710);
FORCEPROP 1 LAST NEEDS_NO_SIZE TRUE
J 0
(-2050 2425);
DISPLAY 0.723404 (-2050 2425);
PAINT GREEN (-2050 2425);
DISPLAY INVISIBLE (-2050 2425);
FORCEPROP 1 LAST CDS_LMAN_SYM_OUTLINE -450,1875,450,-1875
J 0
(-2050 2425);
DISPLAY 0.468085 (-2050 2425);
PAINT GREEN (-2050 2425);
DISPLAY INVISIBLE (-2050 2425);
FORCEPROP 2 LAST CDS_LIB pure_quanta
J 0
(-2050 2425);
DISPLAY INVISIBLE (-2050 2425);
FORCEPROP 2 LAST CDS_LOCATION J5
J 0
(-2500 4650);
DISPLAY 1.021277 (-2500 4650);
DISPLAY INVISIBLE (-2500 4650);
FORCEPROP 0 LAST $SEC 1
J 0
(-2475 4650);
DISPLAY 0.680851 (-2475 4650);
PAINT MONO (-2475 4650);
DISPLAY INVISIBLE (-2475 4650);
FORCEPROP 2 LAST CDS_SEC 1
J 0
(-2500 4650);
DISPLAY 1.021277 (-2500 4650);
DISPLAY INVISIBLE (-2500 4650);
FORCEPROP 1 LAST PATH I24
J 0
(-2050 2425);
DISPLAY 0.723404 (-2050 2425);
PAINT GREEN (-2050 2425);
DISPLAY INVISIBLE (-2050 2425);
FORCEADD TAP..1
R 2
(-2875 1950);
FORCEPROP 3 LASTPIN (-2825 1950) SIG_NAME M_C_CPU0_SB_CB<0>
J 0
(-2815 1960);
DISPLAY 0.659574 (-2815 1960);
PAINT MONO (-2815 1960);
DISPLAY INVISIBLE (-2815 1960);
FORCEPROP 1 LASTPIN (-2825 1950) BN 0
J 2
(-2813 1958);
DISPLAY 0.680851 (-2813 1958);
PAINT GREEN (-2813 1958);
FORCEPROP 2 LAST CDS_LIB standard
J 0
(-2875 1950);
PAINT MONO (-2875 1950);
DISPLAY INVISIBLE (-2875 1950);
FORCEPROP 1 LAST BODY_TYPE PLUMBING
J 2
(-2875 2000);
DISPLAY 0.872340 (-2875 2000);
PAINT GREEN (-2875 2000);
DISPLAY INVISIBLE (-2875 2000);
FORCEPROP 1 LAST HDL_TAP TRUE
J 2
(-3200 1825);
DISPLAY 0.872340 (-3200 1825);
DISPLAY INVISIBLE (-3200 1825);
FORCEPROP 1 LAST PATH I25
J 2
(-2873 1950);
DISPLAY 0.872340 (-2873 1950);
PAINT GREEN (-2873 1950);
DISPLAY INVISIBLE (-2873 1950);
FORCEADD TAP..1
R 2
(-2875 2000);
FORCEPROP 3 LASTPIN (-2825 2000) SIG_NAME M_C_CPU0_SB_CB<1>
J 0
(-2815 2010);
DISPLAY 0.659574 (-2815 2010);
PAINT MONO (-2815 2010);
DISPLAY INVISIBLE (-2815 2010);
FORCEPROP 1 LASTPIN (-2825 2000) BN 1
J 2
(-2813 2008);
DISPLAY 0.680851 (-2813 2008);
PAINT GREEN (-2813 2008);
FORCEPROP 2 LAST CDS_LIB standard
J 0
(-2875 2000);
DISPLAY INVISIBLE (-2875 2000);
FORCEPROP 1 LAST BODY_TYPE PLUMBING
J 2
(-2875 2050);
DISPLAY 0.872340 (-2875 2050);
PAINT GREEN (-2875 2050);
DISPLAY INVISIBLE (-2875 2050);
FORCEPROP 1 LAST HDL_TAP TRUE
J 2
(-3200 1875);
DISPLAY 0.872340 (-3200 1875);
DISPLAY INVISIBLE (-3200 1875);
FORCEPROP 1 LAST PATH I26
J 2
(-2873 2000);
DISPLAY 0.872340 (-2873 2000);
PAINT GREEN (-2873 2000);
DISPLAY INVISIBLE (-2873 2000);
FORCEADD TAP..1
R 2
(-2875 2100);
FORCEPROP 3 LASTPIN (-2825 2100) SIG_NAME M_C_CPU0_SB_CB<3>
J 0
(-2815 2110);
DISPLAY 0.659574 (-2815 2110);
PAINT MONO (-2815 2110);
DISPLAY INVISIBLE (-2815 2110);
FORCEPROP 1 LASTPIN (-2825 2100) BN 3
J 2
(-2813 2108);
DISPLAY 0.680851 (-2813 2108);
PAINT GREEN (-2813 2108);
FORCEPROP 2 LAST CDS_LIB standard
J 0
(-2875 2100);
DISPLAY INVISIBLE (-2875 2100);
FORCEPROP 1 LAST BODY_TYPE PLUMBING
J 2
(-2875 2150);
DISPLAY 0.872340 (-2875 2150);
PAINT GREEN (-2875 2150);
DISPLAY INVISIBLE (-2875 2150);
FORCEPROP 1 LAST HDL_TAP TRUE
J 2
(-3200 1975);
DISPLAY 0.872340 (-3200 1975);
DISPLAY INVISIBLE (-3200 1975);
FORCEPROP 1 LAST PATH I27
J 2
(-2873 2100);
DISPLAY 0.872340 (-2873 2100);
PAINT GREEN (-2873 2100);
DISPLAY INVISIBLE (-2873 2100);
FORCEADD TAP..1
R 2
(-2875 2050);
FORCEPROP 3 LASTPIN (-2825 2050) SIG_NAME M_C_CPU0_SB_CB<2>
J 0
(-2815 2060);
DISPLAY 0.659574 (-2815 2060);
PAINT MONO (-2815 2060);
DISPLAY INVISIBLE (-2815 2060);
FORCEPROP 1 LASTPIN (-2825 2050) BN 2
J 2
(-2813 2058);
DISPLAY 0.680851 (-2813 2058);
PAINT GREEN (-2813 2058);
FORCEPROP 2 LAST CDS_LIB standard
J 0
(-2875 2050);
DISPLAY INVISIBLE (-2875 2050);
FORCEPROP 1 LAST BODY_TYPE PLUMBING
J 2
(-2875 2100);
DISPLAY 0.872340 (-2875 2100);
PAINT GREEN (-2875 2100);
DISPLAY INVISIBLE (-2875 2100);
FORCEPROP 1 LAST HDL_TAP TRUE
J 2
(-3200 1925);
DISPLAY 0.872340 (-3200 1925);
DISPLAY INVISIBLE (-3200 1925);
FORCEPROP 1 LAST PATH I28
J 2
(-2873 2050);
DISPLAY 0.872340 (-2873 2050);
PAINT GREEN (-2873 2050);
DISPLAY INVISIBLE (-2873 2050);
FORCEADD TAP..1
R 2
(-2875 2200);
FORCEPROP 3 LASTPIN (-2825 2200) SIG_NAME M_C_CPU0_SB_CB<5>
J 0
(-2815 2210);
DISPLAY 0.659574 (-2815 2210);
PAINT MONO (-2815 2210);
DISPLAY INVISIBLE (-2815 2210);
FORCEPROP 1 LASTPIN (-2825 2200) BN 5
J 2
(-2813 2208);
DISPLAY 0.680851 (-2813 2208);
PAINT GREEN (-2813 2208);
FORCEPROP 2 LAST CDS_LIB standard
J 0
(-2875 2200);
DISPLAY INVISIBLE (-2875 2200);
FORCEPROP 1 LAST BODY_TYPE PLUMBING
J 2
(-2875 2250);
DISPLAY 0.872340 (-2875 2250);
PAINT GREEN (-2875 2250);
DISPLAY INVISIBLE (-2875 2250);
FORCEPROP 1 LAST HDL_TAP TRUE
J 2
(-3200 2075);
DISPLAY 0.872340 (-3200 2075);
DISPLAY INVISIBLE (-3200 2075);
FORCEPROP 1 LAST PATH I29
J 2
(-2873 2200);
DISPLAY 0.872340 (-2873 2200);
PAINT GREEN (-2873 2200);
DISPLAY INVISIBLE (-2873 2200);
FORCEADD Q_RES..2
(-2650 0);
FORCEPROP 1 LAST PART_NUMBER CS35492FB03
J 0
(-2610 -125);
DISPLAY 0.978723 (-2610 -125);
DISPLAY INVISIBLE (-2610 -125);
FORCEPROP 1 LAST WATTAGE 1/16W
J 0
(-2610 -25);
DISPLAY 0.978723 (-2610 -25);
FORCEPROP 1 LAST MATERIAL CHIP
J 0
(-2610 -75);
DISPLAY 0.978723 (-2610 -75);
FORCEPROP 1 LAST PACK_TYPE 0402LF
J 0
(-2610 -175);
DISPLAY 0.978723 (-2610 -175);
FORCEPROP 1 LAST TOLERANCE 1%
J 0
(-2605 25);
DISPLAY 0.978723 (-2605 25);
FORCEPROP 1 LAST VALUE 54.9K
J 0
(-2605 75);
DISPLAY 0.978723 (-2605 75);
FORCEPROP 1 LAST $LOCATION R30
J 0
(-2605 125);
DISPLAY 0.978723 (-2605 125);
FORCEPROP 1 LASTPIN (-2650 100) $PN 1
J 0
(-2645 62);
DISPLAY 0.787234 (-2645 62);
FORCEPROP 1 LASTPIN (-2650 -100) $PN 2
J 0
(-2645 -90);
DISPLAY 0.787234 (-2645 -90);
FORCEPROP 2 LAST CDS_LIB pure_quanta
J 0
(-2650 0);
PAINT MONO (-2650 0);
DISPLAY INVISIBLE (-2650 0);
FORCEPROP 2 LAST CDS_LOCATION R30
J 0
(-2600 225);
DISPLAY 1.021277 (-2600 225);
DISPLAY INVISIBLE (-2600 225);
FORCEPROP 2 LAST $SEC 1
J 0
(-2600 225);
DISPLAY 0.680851 (-2600 225);
PAINT MONO (-2600 225);
DISPLAY INVISIBLE (-2600 225);
FORCEPROP 2 LAST CDS_SEC 1
J 0
(-2600 225);
DISPLAY 1.021277 (-2600 225);
DISPLAY INVISIBLE (-2600 225);
FORCEPROP 1 LAST PATH I3
J 0
(-2600 175);
DISPLAY 0.978723 (-2600 175);
PAINT WHITE (-2600 175);
DISPLAY INVISIBLE (-2600 175);
FORCEADD TAP..1
R 2
(-2875 2250);
FORCEPROP 3 LASTPIN (-2825 2250) SIG_NAME M_C_CPU0_SB_CB<6>
J 0
(-2815 2260);
DISPLAY 0.659574 (-2815 2260);
PAINT MONO (-2815 2260);
DISPLAY INVISIBLE (-2815 2260);
FORCEPROP 1 LASTPIN (-2825 2250) BN 6
J 2
(-2813 2258);
DISPLAY 0.680851 (-2813 2258);
PAINT GREEN (-2813 2258);
FORCEPROP 2 LAST CDS_LIB standard
J 0
(-2875 2250);
DISPLAY INVISIBLE (-2875 2250);
FORCEPROP 1 LAST BODY_TYPE PLUMBING
J 2
(-2875 2300);
DISPLAY 0.872340 (-2875 2300);
PAINT GREEN (-2875 2300);
DISPLAY INVISIBLE (-2875 2300);
FORCEPROP 1 LAST HDL_TAP TRUE
J 2
(-3200 2125);
DISPLAY 0.872340 (-3200 2125);
DISPLAY INVISIBLE (-3200 2125);
FORCEPROP 1 LAST PATH I30
J 2
(-2873 2250);
DISPLAY 0.872340 (-2873 2250);
PAINT GREEN (-2873 2250);
DISPLAY INVISIBLE (-2873 2250);
FORCEADD TAP..1
R 2
(-2875 2150);
FORCEPROP 3 LASTPIN (-2825 2150) SIG_NAME M_C_CPU0_SB_CB<4>
J 0
(-2815 2160);
DISPLAY 0.659574 (-2815 2160);
PAINT MONO (-2815 2160);
DISPLAY INVISIBLE (-2815 2160);
FORCEPROP 1 LASTPIN (-2825 2150) BN 4
J 2
(-2813 2158);
DISPLAY 0.680851 (-2813 2158);
PAINT GREEN (-2813 2158);
FORCEPROP 2 LAST CDS_LIB standard
J 0
(-2875 2150);
DISPLAY INVISIBLE (-2875 2150);
FORCEPROP 1 LAST BODY_TYPE PLUMBING
J 2
(-2875 2200);
DISPLAY 0.872340 (-2875 2200);
PAINT GREEN (-2875 2200);
DISPLAY INVISIBLE (-2875 2200);
FORCEPROP 1 LAST HDL_TAP TRUE
J 2
(-3200 2025);
DISPLAY 0.872340 (-3200 2025);
DISPLAY INVISIBLE (-3200 2025);
FORCEPROP 1 LAST PATH I31
J 2
(-2873 2150);
DISPLAY 0.872340 (-2873 2150);
PAINT GREEN (-2873 2150);
DISPLAY INVISIBLE (-2873 2150);
FORCEADD TAP..1
(-1225 1000);
FORCEPROP 3 LASTPIN (-1275 1000) SIG_NAME M_C_CPU0_SB_DQ<1>
J 0
(-1265 1010);
DISPLAY 0.659574 (-1265 1010);
PAINT MONO (-1265 1010);
DISPLAY INVISIBLE (-1265 1010);
FORCEPROP 1 LASTPIN (-1275 1000) BN 1
J 0
(-1287 1008);
DISPLAY 0.680851 (-1287 1008);
PAINT GREEN (-1287 1008);
FORCEPROP 2 LAST CDS_LIB standard
J 0
(-1225 1000);
PAINT MONO (-1225 1000);
DISPLAY INVISIBLE (-1225 1000);
FORCEPROP 1 LAST BODY_TYPE PLUMBING
J 0
(-1225 1050);
DISPLAY 0.872340 (-1225 1050);
PAINT GREEN (-1225 1050);
DISPLAY INVISIBLE (-1225 1050);
FORCEPROP 1 LAST HDL_TAP TRUE
J 0
(-900 875);
DISPLAY 0.872340 (-900 875);
DISPLAY INVISIBLE (-900 875);
FORCEPROP 1 LAST PATH I32
J 0
(-1227 1000);
DISPLAY 0.872340 (-1227 1000);
PAINT GREEN (-1227 1000);
DISPLAY INVISIBLE (-1227 1000);
FORCEADD TAP..1
(-1225 950);
FORCEPROP 3 LASTPIN (-1275 950) SIG_NAME M_C_CPU0_SB_DQ<0>
J 0
(-1265 960);
DISPLAY 0.659574 (-1265 960);
PAINT MONO (-1265 960);
DISPLAY INVISIBLE (-1265 960);
FORCEPROP 1 LASTPIN (-1275 950) BN 0
J 0
(-1287 958);
DISPLAY 0.680851 (-1287 958);
PAINT GREEN (-1287 958);
FORCEPROP 2 LAST CDS_LIB standard
J 0
(-1225 950);
PAINT MONO (-1225 950);
DISPLAY INVISIBLE (-1225 950);
FORCEPROP 1 LAST BODY_TYPE PLUMBING
J 0
(-1225 1000);
DISPLAY 0.872340 (-1225 1000);
PAINT GREEN (-1225 1000);
DISPLAY INVISIBLE (-1225 1000);
FORCEPROP 1 LAST HDL_TAP TRUE
J 0
(-900 825);
DISPLAY 0.872340 (-900 825);
DISPLAY INVISIBLE (-900 825);
FORCEPROP 1 LAST PATH I33
J 0
(-1227 950);
DISPLAY 0.872340 (-1227 950);
PAINT GREEN (-1227 950);
DISPLAY INVISIBLE (-1227 950);
FORCEADD TAP..1
(-1225 1100);
FORCEPROP 3 LASTPIN (-1275 1100) SIG_NAME M_C_CPU0_SB_DQ<3>
J 0
(-1265 1110);
DISPLAY 0.659574 (-1265 1110);
PAINT MONO (-1265 1110);
DISPLAY INVISIBLE (-1265 1110);
FORCEPROP 1 LASTPIN (-1275 1100) BN 3
J 0
(-1287 1108);
DISPLAY 0.680851 (-1287 1108);
PAINT GREEN (-1287 1108);
FORCEPROP 2 LAST CDS_LIB standard
J 0
(-1225 1100);
PAINT MONO (-1225 1100);
DISPLAY INVISIBLE (-1225 1100);
FORCEPROP 1 LAST BODY_TYPE PLUMBING
J 0
(-1225 1150);
DISPLAY 0.872340 (-1225 1150);
PAINT GREEN (-1225 1150);
DISPLAY INVISIBLE (-1225 1150);
FORCEPROP 1 LAST HDL_TAP TRUE
J 0
(-900 975);
DISPLAY 0.872340 (-900 975);
DISPLAY INVISIBLE (-900 975);
FORCEPROP 1 LAST PATH I34
J 0
(-1227 1100);
DISPLAY 0.872340 (-1227 1100);
PAINT GREEN (-1227 1100);
DISPLAY INVISIBLE (-1227 1100);
FORCEADD TAP..1
(-1225 1050);
FORCEPROP 3 LASTPIN (-1275 1050) SIG_NAME M_C_CPU0_SB_DQ<2>
J 0
(-1265 1060);
DISPLAY 0.659574 (-1265 1060);
PAINT MONO (-1265 1060);
DISPLAY INVISIBLE (-1265 1060);
FORCEPROP 1 LASTPIN (-1275 1050) BN 2
J 0
(-1287 1058);
DISPLAY 0.680851 (-1287 1058);
PAINT GREEN (-1287 1058);
FORCEPROP 2 LAST CDS_LIB standard
J 0
(-1225 1050);
PAINT MONO (-1225 1050);
DISPLAY INVISIBLE (-1225 1050);
FORCEPROP 1 LAST BODY_TYPE PLUMBING
J 0
(-1225 1100);
DISPLAY 0.872340 (-1225 1100);
PAINT GREEN (-1225 1100);
DISPLAY INVISIBLE (-1225 1100);
FORCEPROP 1 LAST HDL_TAP TRUE
J 0
(-900 925);
DISPLAY 0.872340 (-900 925);
DISPLAY INVISIBLE (-900 925);
FORCEPROP 1 LAST PATH I35
J 0
(-1227 1050);
DISPLAY 0.872340 (-1227 1050);
PAINT GREEN (-1227 1050);
DISPLAY INVISIBLE (-1227 1050);
FORCEADD TAP..1
(-1225 1150);
FORCEPROP 3 LASTPIN (-1275 1150) SIG_NAME M_C_CPU0_SB_DQ<4>
J 0
(-1265 1160);
DISPLAY 0.659574 (-1265 1160);
PAINT MONO (-1265 1160);
DISPLAY INVISIBLE (-1265 1160);
FORCEPROP 1 LASTPIN (-1275 1150) BN 4
J 0
(-1287 1158);
DISPLAY 0.680851 (-1287 1158);
PAINT GREEN (-1287 1158);
FORCEPROP 2 LAST CDS_LIB standard
J 0
(-1225 1150);
PAINT MONO (-1225 1150);
DISPLAY INVISIBLE (-1225 1150);
FORCEPROP 1 LAST BODY_TYPE PLUMBING
J 0
(-1225 1200);
DISPLAY 0.872340 (-1225 1200);
PAINT GREEN (-1225 1200);
DISPLAY INVISIBLE (-1225 1200);
FORCEPROP 1 LAST HDL_TAP TRUE
J 0
(-900 1025);
DISPLAY 0.872340 (-900 1025);
DISPLAY INVISIBLE (-900 1025);
FORCEPROP 1 LAST PATH I36
J 0
(-1227 1150);
DISPLAY 0.872340 (-1227 1150);
PAINT GREEN (-1227 1150);
DISPLAY INVISIBLE (-1227 1150);
FORCEADD TAP..1
(-1225 1200);
FORCEPROP 3 LASTPIN (-1275 1200) SIG_NAME M_C_CPU0_SB_DQ<5>
J 0
(-1265 1210);
DISPLAY 0.659574 (-1265 1210);
PAINT MONO (-1265 1210);
DISPLAY INVISIBLE (-1265 1210);
FORCEPROP 1 LASTPIN (-1275 1200) BN 5
J 0
(-1287 1208);
DISPLAY 0.680851 (-1287 1208);
PAINT GREEN (-1287 1208);
FORCEPROP 2 LAST CDS_LIB standard
J 0
(-1225 1200);
PAINT MONO (-1225 1200);
DISPLAY INVISIBLE (-1225 1200);
FORCEPROP 1 LAST BODY_TYPE PLUMBING
J 0
(-1225 1250);
DISPLAY 0.872340 (-1225 1250);
PAINT GREEN (-1225 1250);
DISPLAY INVISIBLE (-1225 1250);
FORCEPROP 1 LAST HDL_TAP TRUE
J 0
(-900 1075);
DISPLAY 0.872340 (-900 1075);
DISPLAY INVISIBLE (-900 1075);
FORCEPROP 1 LAST PATH I37
J 0
(-1227 1200);
DISPLAY 0.872340 (-1227 1200);
PAINT GREEN (-1227 1200);
DISPLAY INVISIBLE (-1227 1200);
FORCEADD TAP..1
(-1225 1250);
FORCEPROP 3 LASTPIN (-1275 1250) SIG_NAME M_C_CPU0_SB_DQ<6>
J 0
(-1265 1260);
DISPLAY 0.659574 (-1265 1260);
PAINT MONO (-1265 1260);
DISPLAY INVISIBLE (-1265 1260);
FORCEPROP 1 LASTPIN (-1275 1250) BN 6
J 0
(-1287 1258);
DISPLAY 0.680851 (-1287 1258);
PAINT GREEN (-1287 1258);
FORCEPROP 2 LAST CDS_LIB standard
J 0
(-1225 1250);
PAINT MONO (-1225 1250);
DISPLAY INVISIBLE (-1225 1250);
FORCEPROP 1 LAST BODY_TYPE PLUMBING
J 0
(-1225 1300);
DISPLAY 0.872340 (-1225 1300);
PAINT GREEN (-1225 1300);
DISPLAY INVISIBLE (-1225 1300);
FORCEPROP 1 LAST HDL_TAP TRUE
J 0
(-900 1125);
DISPLAY 0.872340 (-900 1125);
DISPLAY INVISIBLE (-900 1125);
FORCEPROP 1 LAST PATH I38
J 0
(-1227 1250);
DISPLAY 0.872340 (-1227 1250);
PAINT GREEN (-1227 1250);
DISPLAY INVISIBLE (-1227 1250);
FORCEADD TAP..1
(-1225 1400);
FORCEPROP 3 LASTPIN (-1275 1400) SIG_NAME M_C_CPU0_SB_DQ<9>
J 0
(-1265 1410);
DISPLAY 0.659574 (-1265 1410);
PAINT MONO (-1265 1410);
DISPLAY INVISIBLE (-1265 1410);
FORCEPROP 1 LASTPIN (-1275 1400) BN 9
J 0
(-1287 1408);
DISPLAY 0.680851 (-1287 1408);
PAINT GREEN (-1287 1408);
FORCEPROP 2 LAST CDS_LIB standard
J 0
(-1225 1400);
PAINT MONO (-1225 1400);
DISPLAY INVISIBLE (-1225 1400);
FORCEPROP 1 LAST BODY_TYPE PLUMBING
J 0
(-1225 1450);
DISPLAY 0.872340 (-1225 1450);
PAINT GREEN (-1225 1450);
DISPLAY INVISIBLE (-1225 1450);
FORCEPROP 1 LAST HDL_TAP TRUE
J 0
(-900 1275);
DISPLAY 0.872340 (-900 1275);
DISPLAY INVISIBLE (-900 1275);
FORCEPROP 1 LAST PATH I39
J 0
(-1227 1400);
DISPLAY 0.872340 (-1227 1400);
PAINT GREEN (-1227 1400);
DISPLAY INVISIBLE (-1227 1400);
FORCEADD OFFPAGE..2
R 2
(-3800 700);
FORCEPROP 2 LAST $XR0 22 
J 0
(-4024 700);
DISPLAY 0.638298 (-4024 700);
PAINT MONO (-4024 700);
FORCEPROP 2 LAST CDS_LIB standard
J 0
(-3800 700);
PAINT MONO (-3800 700);
DISPLAY INVISIBLE (-3800 700);
FORCEPROP 1 LAST OFFPAGE TRUE
J 2
(-4125 575);
DISPLAY 0.872340 (-4125 575);
DISPLAY INVISIBLE (-4125 575);
FORCEPROP 1 LAST COMMENT_BODY TRUE
J 2
(-3755 605);
DISPLAY 0.872340 (-3755 605);
PAINT GREEN (-3755 605);
DISPLAY INVISIBLE (-3755 605);
FORCEPROP 2 LAST PATH I4
J 0
(-3750 775);
DISPLAY 1.021277 (-3750 775);
DISPLAY INVISIBLE (-3750 775);
FORCEADD TAP..1
(-1225 1300);
FORCEPROP 3 LASTPIN (-1275 1300) SIG_NAME M_C_CPU0_SB_DQ<7>
J 0
(-1265 1310);
DISPLAY 0.659574 (-1265 1310);
PAINT MONO (-1265 1310);
DISPLAY INVISIBLE (-1265 1310);
FORCEPROP 1 LASTPIN (-1275 1300) BN 7
J 0
(-1287 1308);
DISPLAY 0.680851 (-1287 1308);
PAINT GREEN (-1287 1308);
FORCEPROP 2 LAST CDS_LIB standard
J 0
(-1225 1300);
PAINT MONO (-1225 1300);
DISPLAY INVISIBLE (-1225 1300);
FORCEPROP 1 LAST BODY_TYPE PLUMBING
J 0
(-1225 1350);
DISPLAY 0.872340 (-1225 1350);
PAINT GREEN (-1225 1350);
DISPLAY INVISIBLE (-1225 1350);
FORCEPROP 1 LAST HDL_TAP TRUE
J 0
(-900 1175);
DISPLAY 0.872340 (-900 1175);
DISPLAY INVISIBLE (-900 1175);
FORCEPROP 1 LAST PATH I40
J 0
(-1227 1300);
DISPLAY 0.872340 (-1227 1300);
PAINT GREEN (-1227 1300);
DISPLAY INVISIBLE (-1227 1300);
FORCEADD TAP..1
(-1225 1350);
FORCEPROP 3 LASTPIN (-1275 1350) SIG_NAME M_C_CPU0_SB_DQ<8>
J 0
(-1265 1360);
DISPLAY 0.659574 (-1265 1360);
PAINT MONO (-1265 1360);
DISPLAY INVISIBLE (-1265 1360);
FORCEPROP 1 LASTPIN (-1275 1350) BN 8
J 0
(-1287 1358);
DISPLAY 0.680851 (-1287 1358);
PAINT GREEN (-1287 1358);
FORCEPROP 2 LAST CDS_LIB standard
J 0
(-1225 1350);
PAINT MONO (-1225 1350);
DISPLAY INVISIBLE (-1225 1350);
FORCEPROP 1 LAST BODY_TYPE PLUMBING
J 0
(-1225 1400);
DISPLAY 0.872340 (-1225 1400);
PAINT GREEN (-1225 1400);
DISPLAY INVISIBLE (-1225 1400);
FORCEPROP 1 LAST HDL_TAP TRUE
J 0
(-900 1225);
DISPLAY 0.872340 (-900 1225);
DISPLAY INVISIBLE (-900 1225);
FORCEPROP 1 LAST PATH I41
J 0
(-1227 1350);
DISPLAY 0.872340 (-1227 1350);
PAINT GREEN (-1227 1350);
DISPLAY INVISIBLE (-1227 1350);
FORCEADD TAP..1
(-1225 1500);
FORCEPROP 3 LASTPIN (-1275 1500) SIG_NAME M_C_CPU0_SB_DQ<11>
J 0
(-1265 1510);
DISPLAY 0.659574 (-1265 1510);
PAINT MONO (-1265 1510);
DISPLAY INVISIBLE (-1265 1510);
FORCEPROP 1 LASTPIN (-1275 1500) BN 11
J 0
(-1287 1508);
DISPLAY 0.680851 (-1287 1508);
PAINT GREEN (-1287 1508);
FORCEPROP 2 LAST CDS_LIB standard
J 0
(-1225 1500);
PAINT MONO (-1225 1500);
DISPLAY INVISIBLE (-1225 1500);
FORCEPROP 1 LAST BODY_TYPE PLUMBING
J 0
(-1225 1550);
DISPLAY 0.872340 (-1225 1550);
PAINT GREEN (-1225 1550);
DISPLAY INVISIBLE (-1225 1550);
FORCEPROP 1 LAST HDL_TAP TRUE
J 0
(-900 1375);
DISPLAY 0.872340 (-900 1375);
DISPLAY INVISIBLE (-900 1375);
FORCEPROP 1 LAST PATH I42
J 0
(-1227 1500);
DISPLAY 0.872340 (-1227 1500);
PAINT GREEN (-1227 1500);
DISPLAY INVISIBLE (-1227 1500);
FORCEADD TAP..1
(-1225 1450);
FORCEPROP 3 LASTPIN (-1275 1450) SIG_NAME M_C_CPU0_SB_DQ<10>
J 0
(-1265 1460);
DISPLAY 0.659574 (-1265 1460);
PAINT MONO (-1265 1460);
DISPLAY INVISIBLE (-1265 1460);
FORCEPROP 1 LASTPIN (-1275 1450) BN 10
J 0
(-1287 1458);
DISPLAY 0.680851 (-1287 1458);
PAINT GREEN (-1287 1458);
FORCEPROP 2 LAST CDS_LIB standard
J 0
(-1225 1450);
PAINT MONO (-1225 1450);
DISPLAY INVISIBLE (-1225 1450);
FORCEPROP 1 LAST BODY_TYPE PLUMBING
J 0
(-1225 1500);
DISPLAY 0.872340 (-1225 1500);
PAINT GREEN (-1225 1500);
DISPLAY INVISIBLE (-1225 1500);
FORCEPROP 1 LAST HDL_TAP TRUE
J 0
(-900 1325);
DISPLAY 0.872340 (-900 1325);
DISPLAY INVISIBLE (-900 1325);
FORCEPROP 1 LAST PATH I43
J 0
(-1227 1450);
DISPLAY 0.872340 (-1227 1450);
PAINT GREEN (-1227 1450);
DISPLAY INVISIBLE (-1227 1450);
FORCEADD TAP..1
(-1225 1600);
FORCEPROP 3 LASTPIN (-1275 1600) SIG_NAME M_C_CPU0_SB_DQ<13>
J 0
(-1265 1610);
DISPLAY 0.659574 (-1265 1610);
PAINT MONO (-1265 1610);
DISPLAY INVISIBLE (-1265 1610);
FORCEPROP 1 LASTPIN (-1275 1600) BN 13
J 0
(-1287 1608);
DISPLAY 0.680851 (-1287 1608);
PAINT GREEN (-1287 1608);
FORCEPROP 2 LAST CDS_LIB standard
J 0
(-1225 1600);
PAINT MONO (-1225 1600);
DISPLAY INVISIBLE (-1225 1600);
FORCEPROP 1 LAST BODY_TYPE PLUMBING
J 0
(-1225 1650);
DISPLAY 0.872340 (-1225 1650);
PAINT GREEN (-1225 1650);
DISPLAY INVISIBLE (-1225 1650);
FORCEPROP 1 LAST HDL_TAP TRUE
J 0
(-900 1475);
DISPLAY 0.872340 (-900 1475);
DISPLAY INVISIBLE (-900 1475);
FORCEPROP 1 LAST PATH I44
J 0
(-1227 1600);
DISPLAY 0.872340 (-1227 1600);
PAINT GREEN (-1227 1600);
DISPLAY INVISIBLE (-1227 1600);
FORCEADD TAP..1
(-1225 1550);
FORCEPROP 3 LASTPIN (-1275 1550) SIG_NAME M_C_CPU0_SB_DQ<12>
J 0
(-1265 1560);
DISPLAY 0.659574 (-1265 1560);
PAINT MONO (-1265 1560);
DISPLAY INVISIBLE (-1265 1560);
FORCEPROP 1 LASTPIN (-1275 1550) BN 12
J 0
(-1287 1558);
DISPLAY 0.680851 (-1287 1558);
PAINT GREEN (-1287 1558);
FORCEPROP 2 LAST CDS_LIB standard
J 0
(-1225 1550);
PAINT MONO (-1225 1550);
DISPLAY INVISIBLE (-1225 1550);
FORCEPROP 1 LAST BODY_TYPE PLUMBING
J 0
(-1225 1600);
DISPLAY 0.872340 (-1225 1600);
PAINT GREEN (-1225 1600);
DISPLAY INVISIBLE (-1225 1600);
FORCEPROP 1 LAST HDL_TAP TRUE
J 0
(-900 1425);
DISPLAY 0.872340 (-900 1425);
DISPLAY INVISIBLE (-900 1425);
FORCEPROP 1 LAST PATH I45
J 0
(-1227 1550);
DISPLAY 0.872340 (-1227 1550);
PAINT GREEN (-1227 1550);
DISPLAY INVISIBLE (-1227 1550);
FORCEADD TAP..1
(-1225 1650);
FORCEPROP 3 LASTPIN (-1275 1650) SIG_NAME M_C_CPU0_SB_DQ<14>
J 0
(-1265 1660);
DISPLAY 0.659574 (-1265 1660);
PAINT MONO (-1265 1660);
DISPLAY INVISIBLE (-1265 1660);
FORCEPROP 1 LASTPIN (-1275 1650) BN 14
J 0
(-1287 1658);
DISPLAY 0.680851 (-1287 1658);
PAINT GREEN (-1287 1658);
FORCEPROP 2 LAST CDS_LIB standard
J 0
(-1225 1650);
PAINT MONO (-1225 1650);
DISPLAY INVISIBLE (-1225 1650);
FORCEPROP 1 LAST BODY_TYPE PLUMBING
J 0
(-1225 1700);
DISPLAY 0.872340 (-1225 1700);
PAINT GREEN (-1225 1700);
DISPLAY INVISIBLE (-1225 1700);
FORCEPROP 1 LAST HDL_TAP TRUE
J 0
(-900 1525);
DISPLAY 0.872340 (-900 1525);
DISPLAY INVISIBLE (-900 1525);
FORCEPROP 1 LAST PATH I46
J 0
(-1227 1650);
DISPLAY 0.872340 (-1227 1650);
PAINT GREEN (-1227 1650);
DISPLAY INVISIBLE (-1227 1650);
FORCEADD TAP..1
(-1225 1700);
FORCEPROP 3 LASTPIN (-1275 1700) SIG_NAME M_C_CPU0_SB_DQ<15>
J 0
(-1265 1710);
DISPLAY 0.659574 (-1265 1710);
PAINT MONO (-1265 1710);
DISPLAY INVISIBLE (-1265 1710);
FORCEPROP 1 LASTPIN (-1275 1700) BN 15
J 0
(-1287 1708);
DISPLAY 0.680851 (-1287 1708);
PAINT GREEN (-1287 1708);
FORCEPROP 2 LAST CDS_LIB standard
J 0
(-1225 1700);
PAINT MONO (-1225 1700);
DISPLAY INVISIBLE (-1225 1700);
FORCEPROP 1 LAST BODY_TYPE PLUMBING
J 0
(-1225 1750);
DISPLAY 0.872340 (-1225 1750);
PAINT GREEN (-1225 1750);
DISPLAY INVISIBLE (-1225 1750);
FORCEPROP 1 LAST HDL_TAP TRUE
J 0
(-900 1575);
DISPLAY 0.872340 (-900 1575);
DISPLAY INVISIBLE (-900 1575);
FORCEPROP 1 LAST PATH I47
J 0
(-1227 1700);
DISPLAY 0.872340 (-1227 1700);
PAINT GREEN (-1227 1700);
DISPLAY INVISIBLE (-1227 1700);
FORCEADD TAP..1
(-1225 1750);
FORCEPROP 3 LASTPIN (-1275 1750) SIG_NAME M_C_CPU0_SB_DQ<16>
J 0
(-1265 1760);
DISPLAY 0.659574 (-1265 1760);
PAINT MONO (-1265 1760);
DISPLAY INVISIBLE (-1265 1760);
FORCEPROP 1 LASTPIN (-1275 1750) BN 16
J 0
(-1287 1758);
DISPLAY 0.680851 (-1287 1758);
PAINT GREEN (-1287 1758);
FORCEPROP 2 LAST CDS_LIB standard
J 0
(-1225 1750);
PAINT MONO (-1225 1750);
DISPLAY INVISIBLE (-1225 1750);
FORCEPROP 1 LAST BODY_TYPE PLUMBING
J 0
(-1225 1800);
DISPLAY 0.872340 (-1225 1800);
PAINT GREEN (-1225 1800);
DISPLAY INVISIBLE (-1225 1800);
FORCEPROP 1 LAST HDL_TAP TRUE
J 0
(-900 1625);
DISPLAY 0.872340 (-900 1625);
DISPLAY INVISIBLE (-900 1625);
FORCEPROP 1 LAST PATH I48
J 0
(-1227 1750);
DISPLAY 0.872340 (-1227 1750);
PAINT GREEN (-1227 1750);
DISPLAY INVISIBLE (-1227 1750);
FORCEADD TAP..1
(-1225 1850);
FORCEPROP 3 LASTPIN (-1275 1850) SIG_NAME M_C_CPU0_SB_DQ<18>
J 0
(-1265 1860);
DISPLAY 0.659574 (-1265 1860);
PAINT MONO (-1265 1860);
DISPLAY INVISIBLE (-1265 1860);
FORCEPROP 1 LASTPIN (-1275 1850) BN 18
J 0
(-1287 1858);
DISPLAY 0.680851 (-1287 1858);
PAINT GREEN (-1287 1858);
FORCEPROP 2 LAST CDS_LIB standard
J 0
(-1225 1850);
PAINT MONO (-1225 1850);
DISPLAY INVISIBLE (-1225 1850);
FORCEPROP 1 LAST BODY_TYPE PLUMBING
J 0
(-1225 1900);
DISPLAY 0.872340 (-1225 1900);
PAINT GREEN (-1225 1900);
DISPLAY INVISIBLE (-1225 1900);
FORCEPROP 1 LAST HDL_TAP TRUE
J 0
(-900 1725);
DISPLAY 0.872340 (-900 1725);
DISPLAY INVISIBLE (-900 1725);
FORCEPROP 1 LAST PATH I49
J 0
(-1227 1850);
DISPLAY 0.872340 (-1227 1850);
PAINT GREEN (-1227 1850);
DISPLAY INVISIBLE (-1227 1850);
FORCEADD OFFPAGE..2
R 2
(-3800 750);
FORCEPROP 2 LAST $XR0 22 
J 0
(-4024 750);
DISPLAY 0.638298 (-4024 750);
PAINT MONO (-4024 750);
FORCEPROP 2 LAST CDS_LIB standard
J 0
(-3800 750);
PAINT MONO (-3800 750);
DISPLAY INVISIBLE (-3800 750);
FORCEPROP 1 LAST OFFPAGE TRUE
J 2
(-4125 625);
DISPLAY 0.872340 (-4125 625);
DISPLAY INVISIBLE (-4125 625);
FORCEPROP 1 LAST COMMENT_BODY TRUE
J 2
(-3755 655);
DISPLAY 0.872340 (-3755 655);
PAINT GREEN (-3755 655);
DISPLAY INVISIBLE (-3755 655);
FORCEPROP 2 LAST PATH I5
J 0
(-3750 825);
DISPLAY 1.021277 (-3750 825);
DISPLAY INVISIBLE (-3750 825);
FORCEADD TAP..1
(-1225 1800);
FORCEPROP 3 LASTPIN (-1275 1800) SIG_NAME M_C_CPU0_SB_DQ<17>
J 0
(-1265 1810);
DISPLAY 0.659574 (-1265 1810);
PAINT MONO (-1265 1810);
DISPLAY INVISIBLE (-1265 1810);
FORCEPROP 1 LASTPIN (-1275 1800) BN 17
J 0
(-1287 1808);
DISPLAY 0.680851 (-1287 1808);
PAINT GREEN (-1287 1808);
FORCEPROP 2 LAST CDS_LIB standard
J 0
(-1225 1800);
PAINT MONO (-1225 1800);
DISPLAY INVISIBLE (-1225 1800);
FORCEPROP 1 LAST BODY_TYPE PLUMBING
J 0
(-1225 1850);
DISPLAY 0.872340 (-1225 1850);
PAINT GREEN (-1225 1850);
DISPLAY INVISIBLE (-1225 1850);
FORCEPROP 1 LAST HDL_TAP TRUE
J 0
(-900 1675);
DISPLAY 0.872340 (-900 1675);
DISPLAY INVISIBLE (-900 1675);
FORCEPROP 1 LAST PATH I50
J 0
(-1227 1800);
DISPLAY 0.872340 (-1227 1800);
PAINT GREEN (-1227 1800);
DISPLAY INVISIBLE (-1227 1800);
FORCEADD TAP..1
(-1225 1900);
FORCEPROP 3 LASTPIN (-1275 1900) SIG_NAME M_C_CPU0_SB_DQ<19>
J 0
(-1265 1910);
DISPLAY 0.659574 (-1265 1910);
PAINT MONO (-1265 1910);
DISPLAY INVISIBLE (-1265 1910);
FORCEPROP 1 LASTPIN (-1275 1900) BN 19
J 0
(-1287 1908);
DISPLAY 0.680851 (-1287 1908);
PAINT GREEN (-1287 1908);
FORCEPROP 2 LAST CDS_LIB standard
J 0
(-1225 1900);
PAINT MONO (-1225 1900);
DISPLAY INVISIBLE (-1225 1900);
FORCEPROP 1 LAST BODY_TYPE PLUMBING
J 0
(-1225 1950);
DISPLAY 0.872340 (-1225 1950);
PAINT GREEN (-1225 1950);
DISPLAY INVISIBLE (-1225 1950);
FORCEPROP 1 LAST HDL_TAP TRUE
J 0
(-900 1775);
DISPLAY 0.872340 (-900 1775);
DISPLAY INVISIBLE (-900 1775);
FORCEPROP 1 LAST PATH I51
J 0
(-1227 1900);
DISPLAY 0.872340 (-1227 1900);
PAINT GREEN (-1227 1900);
DISPLAY INVISIBLE (-1227 1900);
FORCEADD TAP..1
(-1225 2000);
FORCEPROP 3 LASTPIN (-1275 2000) SIG_NAME M_C_CPU0_SB_DQ<21>
J 0
(-1265 2010);
DISPLAY 0.659574 (-1265 2010);
PAINT MONO (-1265 2010);
DISPLAY INVISIBLE (-1265 2010);
FORCEPROP 1 LASTPIN (-1275 2000) BN 21
J 0
(-1287 2008);
DISPLAY 0.680851 (-1287 2008);
PAINT GREEN (-1287 2008);
FORCEPROP 2 LAST CDS_LIB standard
J 0
(-1225 2000);
PAINT MONO (-1225 2000);
DISPLAY INVISIBLE (-1225 2000);
FORCEPROP 1 LAST BODY_TYPE PLUMBING
J 0
(-1225 2050);
DISPLAY 0.872340 (-1225 2050);
PAINT GREEN (-1225 2050);
DISPLAY INVISIBLE (-1225 2050);
FORCEPROP 1 LAST HDL_TAP TRUE
J 0
(-900 1875);
DISPLAY 0.872340 (-900 1875);
DISPLAY INVISIBLE (-900 1875);
FORCEPROP 1 LAST PATH I52
J 0
(-1227 2000);
DISPLAY 0.872340 (-1227 2000);
PAINT GREEN (-1227 2000);
DISPLAY INVISIBLE (-1227 2000);
FORCEADD TAP..1
(-1225 1950);
FORCEPROP 3 LASTPIN (-1275 1950) SIG_NAME M_C_CPU0_SB_DQ<20>
J 0
(-1265 1960);
DISPLAY 0.659574 (-1265 1960);
PAINT MONO (-1265 1960);
DISPLAY INVISIBLE (-1265 1960);
FORCEPROP 1 LASTPIN (-1275 1950) BN 20
J 0
(-1287 1958);
DISPLAY 0.680851 (-1287 1958);
PAINT GREEN (-1287 1958);
FORCEPROP 2 LAST CDS_LIB standard
J 0
(-1225 1950);
PAINT MONO (-1225 1950);
DISPLAY INVISIBLE (-1225 1950);
FORCEPROP 1 LAST BODY_TYPE PLUMBING
J 0
(-1225 2000);
DISPLAY 0.872340 (-1225 2000);
PAINT GREEN (-1225 2000);
DISPLAY INVISIBLE (-1225 2000);
FORCEPROP 1 LAST HDL_TAP TRUE
J 0
(-900 1825);
DISPLAY 0.872340 (-900 1825);
DISPLAY INVISIBLE (-900 1825);
FORCEPROP 1 LAST PATH I53
J 0
(-1227 1950);
DISPLAY 0.872340 (-1227 1950);
PAINT GREEN (-1227 1950);
DISPLAY INVISIBLE (-1227 1950);
FORCEADD TAP..1
(-1225 2150);
FORCEPROP 3 LASTPIN (-1275 2150) SIG_NAME M_C_CPU0_SB_DQ<24>
J 0
(-1265 2160);
DISPLAY 0.659574 (-1265 2160);
PAINT MONO (-1265 2160);
DISPLAY INVISIBLE (-1265 2160);
FORCEPROP 1 LASTPIN (-1275 2150) BN 24
J 0
(-1287 2158);
DISPLAY 0.680851 (-1287 2158);
PAINT GREEN (-1287 2158);
FORCEPROP 2 LAST CDS_LIB standard
J 0
(-1225 2150);
DISPLAY INVISIBLE (-1225 2150);
FORCEPROP 1 LAST BODY_TYPE PLUMBING
J 0
(-1225 2200);
DISPLAY 0.872340 (-1225 2200);
PAINT GREEN (-1225 2200);
DISPLAY INVISIBLE (-1225 2200);
FORCEPROP 1 LAST HDL_TAP TRUE
J 0
(-900 2025);
DISPLAY 0.872340 (-900 2025);
DISPLAY INVISIBLE (-900 2025);
FORCEPROP 1 LAST PATH I54
J 0
(-1227 2150);
DISPLAY 0.872340 (-1227 2150);
PAINT GREEN (-1227 2150);
DISPLAY INVISIBLE (-1227 2150);
FORCEADD TAP..1
(-1225 2100);
FORCEPROP 3 LASTPIN (-1275 2100) SIG_NAME M_C_CPU0_SB_DQ<23>
J 0
(-1265 2110);
DISPLAY 0.659574 (-1265 2110);
PAINT MONO (-1265 2110);
DISPLAY INVISIBLE (-1265 2110);
FORCEPROP 1 LASTPIN (-1275 2100) BN 23
J 0
(-1287 2108);
DISPLAY 0.680851 (-1287 2108);
PAINT GREEN (-1287 2108);
FORCEPROP 2 LAST CDS_LIB standard
J 0
(-1225 2100);
DISPLAY INVISIBLE (-1225 2100);
FORCEPROP 1 LAST BODY_TYPE PLUMBING
J 0
(-1225 2150);
DISPLAY 0.872340 (-1225 2150);
PAINT GREEN (-1225 2150);
DISPLAY INVISIBLE (-1225 2150);
FORCEPROP 1 LAST HDL_TAP TRUE
J 0
(-900 1975);
DISPLAY 0.872340 (-900 1975);
DISPLAY INVISIBLE (-900 1975);
FORCEPROP 1 LAST PATH I55
J 0
(-1227 2100);
DISPLAY 0.872340 (-1227 2100);
PAINT GREEN (-1227 2100);
DISPLAY INVISIBLE (-1227 2100);
FORCEADD TAP..1
(-1225 2050);
FORCEPROP 3 LASTPIN (-1275 2050) SIG_NAME M_C_CPU0_SB_DQ<22>
J 0
(-1265 2060);
DISPLAY 0.659574 (-1265 2060);
PAINT MONO (-1265 2060);
DISPLAY INVISIBLE (-1265 2060);
FORCEPROP 1 LASTPIN (-1275 2050) BN 22
J 0
(-1287 2058);
DISPLAY 0.680851 (-1287 2058);
PAINT GREEN (-1287 2058);
FORCEPROP 2 LAST CDS_LIB standard
J 0
(-1225 2050);
DISPLAY INVISIBLE (-1225 2050);
FORCEPROP 1 LAST BODY_TYPE PLUMBING
J 0
(-1225 2100);
DISPLAY 0.872340 (-1225 2100);
PAINT GREEN (-1225 2100);
DISPLAY INVISIBLE (-1225 2100);
FORCEPROP 1 LAST HDL_TAP TRUE
J 0
(-900 1925);
DISPLAY 0.872340 (-900 1925);
DISPLAY INVISIBLE (-900 1925);
FORCEPROP 1 LAST PATH I56
J 0
(-1227 2050);
DISPLAY 0.872340 (-1227 2050);
PAINT GREEN (-1227 2050);
DISPLAY INVISIBLE (-1227 2050);
FORCEADD TAP..1
(-1225 2200);
FORCEPROP 3 LASTPIN (-1275 2200) SIG_NAME M_C_CPU0_SB_DQ<25>
J 0
(-1265 2210);
DISPLAY 0.659574 (-1265 2210);
PAINT MONO (-1265 2210);
DISPLAY INVISIBLE (-1265 2210);
FORCEPROP 1 LASTPIN (-1275 2200) BN 25
J 0
(-1287 2208);
DISPLAY 0.680851 (-1287 2208);
PAINT GREEN (-1287 2208);
FORCEPROP 2 LAST CDS_LIB standard
J 0
(-1225 2200);
DISPLAY INVISIBLE (-1225 2200);
FORCEPROP 1 LAST BODY_TYPE PLUMBING
J 0
(-1225 2250);
DISPLAY 0.872340 (-1225 2250);
PAINT GREEN (-1225 2250);
DISPLAY INVISIBLE (-1225 2250);
FORCEPROP 1 LAST HDL_TAP TRUE
J 0
(-900 2075);
DISPLAY 0.872340 (-900 2075);
DISPLAY INVISIBLE (-900 2075);
FORCEPROP 1 LAST PATH I57
J 0
(-1227 2200);
DISPLAY 0.872340 (-1227 2200);
PAINT GREEN (-1227 2200);
DISPLAY INVISIBLE (-1227 2200);
FORCEADD TAP..1
(-1225 2250);
FORCEPROP 3 LASTPIN (-1275 2250) SIG_NAME M_C_CPU0_SB_DQ<26>
J 0
(-1265 2260);
DISPLAY 0.659574 (-1265 2260);
PAINT MONO (-1265 2260);
DISPLAY INVISIBLE (-1265 2260);
FORCEPROP 1 LASTPIN (-1275 2250) BN 26
J 0
(-1287 2258);
DISPLAY 0.680851 (-1287 2258);
PAINT GREEN (-1287 2258);
FORCEPROP 2 LAST CDS_LIB standard
J 0
(-1225 2250);
DISPLAY INVISIBLE (-1225 2250);
FORCEPROP 1 LAST BODY_TYPE PLUMBING
J 0
(-1225 2300);
DISPLAY 0.872340 (-1225 2300);
PAINT GREEN (-1225 2300);
DISPLAY INVISIBLE (-1225 2300);
FORCEPROP 1 LAST HDL_TAP TRUE
J 0
(-900 2125);
DISPLAY 0.872340 (-900 2125);
DISPLAY INVISIBLE (-900 2125);
FORCEPROP 1 LAST PATH I58
J 0
(-1227 2250);
DISPLAY 0.872340 (-1227 2250);
PAINT GREEN (-1227 2250);
DISPLAY INVISIBLE (-1227 2250);
FORCEADD TAP..1
R 2
(-2875 2500);
FORCEPROP 3 LASTPIN (-2825 2500) SIG_NAME M_C_CPU0_SA_CB<2>
J 0
(-2815 2510);
DISPLAY 0.659574 (-2815 2510);
PAINT MONO (-2815 2510);
DISPLAY INVISIBLE (-2815 2510);
FORCEPROP 1 LASTPIN (-2825 2500) BN 2
J 2
(-2813 2508);
DISPLAY 0.680851 (-2813 2508);
PAINT GREEN (-2813 2508);
FORCEPROP 2 LAST CDS_LIB standard
J 0
(-2875 2500);
DISPLAY INVISIBLE (-2875 2500);
FORCEPROP 1 LAST BODY_TYPE PLUMBING
J 2
(-2875 2550);
DISPLAY 0.872340 (-2875 2550);
PAINT GREEN (-2875 2550);
DISPLAY INVISIBLE (-2875 2550);
FORCEPROP 1 LAST HDL_TAP TRUE
J 2
(-3200 2375);
DISPLAY 0.872340 (-3200 2375);
DISPLAY INVISIBLE (-3200 2375);
FORCEPROP 1 LAST PATH I59
J 2
(-2873 2500);
DISPLAY 0.872340 (-2873 2500);
PAINT GREEN (-2873 2500);
DISPLAY INVISIBLE (-2873 2500);
FORCEADD TAP..1
R 2
(-2875 2450);
FORCEPROP 3 LASTPIN (-2825 2450) SIG_NAME M_C_CPU0_SA_CB<1>
J 0
(-2815 2460);
DISPLAY 0.659574 (-2815 2460);
PAINT MONO (-2815 2460);
DISPLAY INVISIBLE (-2815 2460);
FORCEPROP 1 LASTPIN (-2825 2450) BN 1
J 2
(-2813 2458);
DISPLAY 0.680851 (-2813 2458);
PAINT GREEN (-2813 2458);
FORCEPROP 2 LAST CDS_LIB standard
J 0
(-2875 2450);
DISPLAY INVISIBLE (-2875 2450);
FORCEPROP 1 LAST BODY_TYPE PLUMBING
J 2
(-2875 2500);
DISPLAY 0.872340 (-2875 2500);
PAINT GREEN (-2875 2500);
DISPLAY INVISIBLE (-2875 2500);
FORCEPROP 1 LAST HDL_TAP TRUE
J 2
(-3200 2325);
DISPLAY 0.872340 (-3200 2325);
DISPLAY INVISIBLE (-3200 2325);
FORCEPROP 1 LAST PATH I60
J 2
(-2873 2450);
DISPLAY 0.872340 (-2873 2450);
PAINT GREEN (-2873 2450);
DISPLAY INVISIBLE (-2873 2450);
FORCEADD TAP..1
R 2
(-2875 2400);
FORCEPROP 3 LASTPIN (-2825 2400) SIG_NAME M_C_CPU0_SA_CB<0>
J 0
(-2815 2410);
DISPLAY 0.659574 (-2815 2410);
PAINT MONO (-2815 2410);
DISPLAY INVISIBLE (-2815 2410);
FORCEPROP 1 LASTPIN (-2825 2400) BN 0
J 2
(-2813 2408);
DISPLAY 0.680851 (-2813 2408);
PAINT GREEN (-2813 2408);
FORCEPROP 2 LAST CDS_LIB standard
J 0
(-2875 2400);
PAINT MONO (-2875 2400);
DISPLAY INVISIBLE (-2875 2400);
FORCEPROP 1 LAST BODY_TYPE PLUMBING
J 2
(-2875 2450);
DISPLAY 0.872340 (-2875 2450);
PAINT GREEN (-2875 2450);
DISPLAY INVISIBLE (-2875 2450);
FORCEPROP 1 LAST HDL_TAP TRUE
J 2
(-3200 2275);
DISPLAY 0.872340 (-3200 2275);
DISPLAY INVISIBLE (-3200 2275);
FORCEPROP 1 LAST PATH I61
J 2
(-2873 2400);
DISPLAY 0.872340 (-2873 2400);
PAINT GREEN (-2873 2400);
DISPLAY INVISIBLE (-2873 2400);
FORCEADD TAP..1
R 2
(-2875 2300);
FORCEPROP 3 LASTPIN (-2825 2300) SIG_NAME M_C_CPU0_SB_CB<7>
J 0
(-2815 2310);
DISPLAY 0.659574 (-2815 2310);
PAINT MONO (-2815 2310);
DISPLAY INVISIBLE (-2815 2310);
FORCEPROP 1 LASTPIN (-2825 2300) BN 7
J 2
(-2813 2308);
DISPLAY 0.680851 (-2813 2308);
PAINT GREEN (-2813 2308);
FORCEPROP 2 LAST CDS_LIB standard
J 0
(-2875 2300);
DISPLAY INVISIBLE (-2875 2300);
FORCEPROP 1 LAST BODY_TYPE PLUMBING
J 2
(-2875 2350);
DISPLAY 0.872340 (-2875 2350);
PAINT GREEN (-2875 2350);
DISPLAY INVISIBLE (-2875 2350);
FORCEPROP 1 LAST HDL_TAP TRUE
J 2
(-3200 2175);
DISPLAY 0.872340 (-3200 2175);
DISPLAY INVISIBLE (-3200 2175);
FORCEPROP 1 LAST PATH I62
J 2
(-2873 2300);
DISPLAY 0.872340 (-2873 2300);
PAINT GREEN (-2873 2300);
DISPLAY INVISIBLE (-2873 2300);
FORCEADD TAP..1
R 2
(-2875 2650);
FORCEPROP 3 LASTPIN (-2825 2650) SIG_NAME M_C_CPU0_SA_CB<5>
J 0
(-2815 2660);
DISPLAY 0.659574 (-2815 2660);
PAINT MONO (-2815 2660);
DISPLAY INVISIBLE (-2815 2660);
FORCEPROP 1 LASTPIN (-2825 2650) BN 5
J 2
(-2813 2658);
DISPLAY 0.680851 (-2813 2658);
PAINT GREEN (-2813 2658);
FORCEPROP 2 LAST CDS_LIB standard
J 0
(-2875 2650);
DISPLAY INVISIBLE (-2875 2650);
FORCEPROP 1 LAST BODY_TYPE PLUMBING
J 2
(-2875 2700);
DISPLAY 0.872340 (-2875 2700);
PAINT GREEN (-2875 2700);
DISPLAY INVISIBLE (-2875 2700);
FORCEPROP 1 LAST HDL_TAP TRUE
J 2
(-3200 2525);
DISPLAY 0.872340 (-3200 2525);
DISPLAY INVISIBLE (-3200 2525);
FORCEPROP 1 LAST PATH I63
J 2
(-2873 2650);
DISPLAY 0.872340 (-2873 2650);
PAINT GREEN (-2873 2650);
DISPLAY INVISIBLE (-2873 2650);
FORCEADD TAP..1
R 2
(-2875 2600);
FORCEPROP 3 LASTPIN (-2825 2600) SIG_NAME M_C_CPU0_SA_CB<4>
J 0
(-2815 2610);
DISPLAY 0.659574 (-2815 2610);
PAINT MONO (-2815 2610);
DISPLAY INVISIBLE (-2815 2610);
FORCEPROP 1 LASTPIN (-2825 2600) BN 4
J 2
(-2813 2608);
DISPLAY 0.680851 (-2813 2608);
PAINT GREEN (-2813 2608);
FORCEPROP 2 LAST CDS_LIB standard
J 0
(-2875 2600);
DISPLAY INVISIBLE (-2875 2600);
FORCEPROP 1 LAST BODY_TYPE PLUMBING
J 2
(-2875 2650);
DISPLAY 0.872340 (-2875 2650);
PAINT GREEN (-2875 2650);
DISPLAY INVISIBLE (-2875 2650);
FORCEPROP 1 LAST HDL_TAP TRUE
J 2
(-3200 2475);
DISPLAY 0.872340 (-3200 2475);
DISPLAY INVISIBLE (-3200 2475);
FORCEPROP 1 LAST PATH I64
J 2
(-2873 2600);
DISPLAY 0.872340 (-2873 2600);
PAINT GREEN (-2873 2600);
DISPLAY INVISIBLE (-2873 2600);
FORCEADD TAP..1
R 2
(-2875 2550);
FORCEPROP 3 LASTPIN (-2825 2550) SIG_NAME M_C_CPU0_SA_CB<3>
J 0
(-2815 2560);
DISPLAY 0.659574 (-2815 2560);
PAINT MONO (-2815 2560);
DISPLAY INVISIBLE (-2815 2560);
FORCEPROP 1 LASTPIN (-2825 2550) BN 3
J 2
(-2813 2558);
DISPLAY 0.680851 (-2813 2558);
PAINT GREEN (-2813 2558);
FORCEPROP 2 LAST CDS_LIB standard
J 0
(-2875 2550);
DISPLAY INVISIBLE (-2875 2550);
FORCEPROP 1 LAST BODY_TYPE PLUMBING
J 2
(-2875 2600);
DISPLAY 0.872340 (-2875 2600);
PAINT GREEN (-2875 2600);
DISPLAY INVISIBLE (-2875 2600);
FORCEPROP 1 LAST HDL_TAP TRUE
J 2
(-3200 2425);
DISPLAY 0.872340 (-3200 2425);
DISPLAY INVISIBLE (-3200 2425);
FORCEPROP 1 LAST PATH I65
J 2
(-2873 2550);
DISPLAY 0.872340 (-2873 2550);
PAINT GREEN (-2873 2550);
DISPLAY INVISIBLE (-2873 2550);
FORCEADD TAP..1
R 2
(-2875 2700);
FORCEPROP 3 LASTPIN (-2825 2700) SIG_NAME M_C_CPU0_SA_CB<6>
J 0
(-2815 2710);
DISPLAY 0.659574 (-2815 2710);
PAINT MONO (-2815 2710);
DISPLAY INVISIBLE (-2815 2710);
FORCEPROP 1 LASTPIN (-2825 2700) BN 6
J 2
(-2813 2708);
DISPLAY 0.680851 (-2813 2708);
PAINT GREEN (-2813 2708);
FORCEPROP 2 LAST CDS_LIB standard
J 0
(-2875 2700);
DISPLAY INVISIBLE (-2875 2700);
FORCEPROP 1 LAST BODY_TYPE PLUMBING
J 2
(-2875 2750);
DISPLAY 0.872340 (-2875 2750);
PAINT GREEN (-2875 2750);
DISPLAY INVISIBLE (-2875 2750);
FORCEPROP 1 LAST HDL_TAP TRUE
J 2
(-3200 2575);
DISPLAY 0.872340 (-3200 2575);
DISPLAY INVISIBLE (-3200 2575);
FORCEPROP 1 LAST PATH I66
J 2
(-2873 2700);
DISPLAY 0.872340 (-2873 2700);
PAINT GREEN (-2873 2700);
DISPLAY INVISIBLE (-2873 2700);
FORCEADD TAP..1
R 2
(-2875 2750);
FORCEPROP 3 LASTPIN (-2825 2750) SIG_NAME M_C_CPU0_SA_CB<7>
J 0
(-2815 2760);
DISPLAY 0.659574 (-2815 2760);
PAINT MONO (-2815 2760);
DISPLAY INVISIBLE (-2815 2760);
FORCEPROP 1 LASTPIN (-2825 2750) BN 7
J 2
(-2813 2758);
DISPLAY 0.680851 (-2813 2758);
PAINT GREEN (-2813 2758);
FORCEPROP 2 LAST CDS_LIB standard
J 0
(-2875 2750);
DISPLAY INVISIBLE (-2875 2750);
FORCEPROP 1 LAST BODY_TYPE PLUMBING
J 2
(-2875 2800);
DISPLAY 0.872340 (-2875 2800);
PAINT GREEN (-2875 2800);
DISPLAY INVISIBLE (-2875 2800);
FORCEPROP 1 LAST HDL_TAP TRUE
J 2
(-3200 2625);
DISPLAY 0.872340 (-3200 2625);
DISPLAY INVISIBLE (-3200 2625);
FORCEPROP 1 LAST PATH I67
J 2
(-2873 2750);
DISPLAY 0.872340 (-2873 2750);
PAINT GREEN (-2873 2750);
DISPLAY INVISIBLE (-2873 2750);
FORCEADD TAP..1
R 2
(-2875 3450);
FORCEPROP 3 LASTPIN (-2825 3450) SIG_NAME M_C_CPU0_SB_CA<0>
J 0
(-2815 3460);
DISPLAY 0.659574 (-2815 3460);
PAINT MONO (-2815 3460);
DISPLAY INVISIBLE (-2815 3460);
FORCEPROP 1 LASTPIN (-2825 3450) BN 0
J 2
(-2813 3458);
DISPLAY 0.680851 (-2813 3458);
PAINT GREEN (-2813 3458);
FORCEPROP 2 LAST CDS_LIB standard
J 0
(-2875 3450);
DISPLAY INVISIBLE (-2875 3450);
FORCEPROP 1 LAST BODY_TYPE PLUMBING
J 2
(-2875 3500);
DISPLAY 0.872340 (-2875 3500);
PAINT GREEN (-2875 3500);
DISPLAY INVISIBLE (-2875 3500);
FORCEPROP 1 LAST HDL_TAP TRUE
J 2
(-3200 3325);
DISPLAY 0.872340 (-3200 3325);
DISPLAY INVISIBLE (-3200 3325);
FORCEPROP 1 LAST PATH I68
J 2
(-2873 3450);
DISPLAY 0.872340 (-2873 3450);
PAINT GREEN (-2873 3450);
DISPLAY INVISIBLE (-2873 3450);
FORCEADD TAP..1
R 2
(-2875 3550);
FORCEPROP 3 LASTPIN (-2825 3550) SIG_NAME M_C_CPU0_SB_CA<2>
J 0
(-2815 3560);
DISPLAY 0.659574 (-2815 3560);
PAINT MONO (-2815 3560);
DISPLAY INVISIBLE (-2815 3560);
FORCEPROP 1 LASTPIN (-2825 3550) BN 2
J 2
(-2813 3558);
DISPLAY 0.680851 (-2813 3558);
PAINT GREEN (-2813 3558);
FORCEPROP 2 LAST CDS_LIB standard
J 0
(-2875 3550);
DISPLAY INVISIBLE (-2875 3550);
FORCEPROP 1 LAST BODY_TYPE PLUMBING
J 2
(-2875 3600);
DISPLAY 0.872340 (-2875 3600);
PAINT GREEN (-2875 3600);
DISPLAY INVISIBLE (-2875 3600);
FORCEPROP 1 LAST HDL_TAP TRUE
J 2
(-3200 3425);
DISPLAY 0.872340 (-3200 3425);
DISPLAY INVISIBLE (-3200 3425);
FORCEPROP 1 LAST PATH I69
J 2
(-2873 3550);
DISPLAY 0.872340 (-2873 3550);
PAINT GREEN (-2873 3550);
DISPLAY INVISIBLE (-2873 3550);
FORCEADD OFFPAGE..1
(-3725 1600);
FORCEPROP 2 LAST $XR7 89 
J 0
(-4097 1636);
DISPLAY 0.638298 (-4097 1636);
PAINT MONO (-4097 1636);
FORCEPROP 2 LAST $XR6 88 
J 0
(-4007 1636);
DISPLAY 0.638298 (-4007 1636);
PAINT MONO (-4007 1636);
FORCEPROP 2 LAST $XR5 87 
J 0
(-4187 1564);
DISPLAY 0.638298 (-4187 1564);
PAINT MONO (-4187 1564);
FORCEPROP 2 LAST $XR4 85 
J 0
(-4097 1564);
DISPLAY 0.638298 (-4097 1564);
PAINT MONO (-4097 1564);
FORCEPROP 2 LAST $XR3 84 
J 0
(-4007 1564);
DISPLAY 0.638298 (-4007 1564);
PAINT MONO (-4007 1564);
FORCEPROP 2 LAST $XR2 83 
J 0
(-4187 1600);
DISPLAY 0.638298 (-4187 1600);
PAINT MONO (-4187 1600);
FORCEPROP 2 LAST $XR1 82 
J 0
(-4097 1600);
DISPLAY 0.638298 (-4097 1600);
PAINT MONO (-4097 1600);
FORCEPROP 2 LAST $XR0 229 
J 0
(-4007 1600);
DISPLAY 0.638298 (-4007 1600);
PAINT MONO (-4007 1600);
FORCEPROP 2 LAST CDS_LIB standard
J 0
(-3725 1600);
PAINT MONO (-3725 1600);
DISPLAY INVISIBLE (-3725 1600);
FORCEPROP 1 LAST OFFPAGE TRUE
J 0
(-3400 1475);
DISPLAY 0.872340 (-3400 1475);
DISPLAY INVISIBLE (-3400 1475);
FORCEPROP 1 LAST COMMENT_BODY TRUE
J 0
(-3600 1500);
DISPLAY 0.872340 (-3600 1500);
PAINT GREEN (-3600 1500);
DISPLAY INVISIBLE (-3600 1500);
FORCEPROP 2 LAST PATH I7
J 0
(-3675 1675);
DISPLAY 1.021277 (-3675 1675);
DISPLAY INVISIBLE (-3675 1675);
FORCEADD TAP..1
R 2
(-2875 3500);
FORCEPROP 3 LASTPIN (-2825 3500) SIG_NAME M_C_CPU0_SB_CA<1>
J 0
(-2815 3510);
DISPLAY 0.659574 (-2815 3510);
PAINT MONO (-2815 3510);
DISPLAY INVISIBLE (-2815 3510);
FORCEPROP 1 LASTPIN (-2825 3500) BN 1
J 2
(-2813 3508);
DISPLAY 0.680851 (-2813 3508);
PAINT GREEN (-2813 3508);
FORCEPROP 2 LAST CDS_LIB standard
J 0
(-2875 3500);
DISPLAY INVISIBLE (-2875 3500);
FORCEPROP 1 LAST BODY_TYPE PLUMBING
J 2
(-2875 3550);
DISPLAY 0.872340 (-2875 3550);
PAINT GREEN (-2875 3550);
DISPLAY INVISIBLE (-2875 3550);
FORCEPROP 1 LAST HDL_TAP TRUE
J 2
(-3200 3375);
DISPLAY 0.872340 (-3200 3375);
DISPLAY INVISIBLE (-3200 3375);
FORCEPROP 1 LAST PATH I70
J 2
(-2873 3500);
DISPLAY 0.872340 (-2873 3500);
PAINT GREEN (-2873 3500);
DISPLAY INVISIBLE (-2873 3500);
FORCEADD TAP..1
R 2
(-2875 3700);
FORCEPROP 3 LASTPIN (-2825 3700) SIG_NAME M_C_CPU0_SB_CA<5>
J 0
(-2815 3710);
DISPLAY 0.659574 (-2815 3710);
PAINT MONO (-2815 3710);
DISPLAY INVISIBLE (-2815 3710);
FORCEPROP 1 LASTPIN (-2825 3700) BN 5
J 2
(-2813 3708);
DISPLAY 0.680851 (-2813 3708);
PAINT GREEN (-2813 3708);
FORCEPROP 2 LAST CDS_LIB standard
J 0
(-2875 3700);
DISPLAY INVISIBLE (-2875 3700);
FORCEPROP 1 LAST BODY_TYPE PLUMBING
J 2
(-2875 3750);
DISPLAY 0.872340 (-2875 3750);
PAINT GREEN (-2875 3750);
DISPLAY INVISIBLE (-2875 3750);
FORCEPROP 1 LAST HDL_TAP TRUE
J 2
(-3200 3575);
DISPLAY 0.872340 (-3200 3575);
DISPLAY INVISIBLE (-3200 3575);
FORCEPROP 1 LAST PATH I71
J 2
(-2873 3700);
DISPLAY 0.872340 (-2873 3700);
PAINT GREEN (-2873 3700);
DISPLAY INVISIBLE (-2873 3700);
FORCEADD TAP..1
R 2
(-2875 3750);
FORCEPROP 3 LASTPIN (-2825 3750) SIG_NAME M_C_CPU0_SB_CA<6>
J 0
(-2815 3760);
DISPLAY 0.659574 (-2815 3760);
PAINT MONO (-2815 3760);
DISPLAY INVISIBLE (-2815 3760);
FORCEPROP 1 LASTPIN (-2825 3750) BN 6
J 2
(-2813 3758);
DISPLAY 0.680851 (-2813 3758);
PAINT GREEN (-2813 3758);
FORCEPROP 2 LAST CDS_LIB standard
J 0
(-2875 3750);
DISPLAY INVISIBLE (-2875 3750);
FORCEPROP 1 LAST BODY_TYPE PLUMBING
J 2
(-2875 3800);
DISPLAY 0.872340 (-2875 3800);
PAINT GREEN (-2875 3800);
DISPLAY INVISIBLE (-2875 3800);
FORCEPROP 1 LAST HDL_TAP TRUE
J 2
(-3200 3625);
DISPLAY 0.872340 (-3200 3625);
DISPLAY INVISIBLE (-3200 3625);
FORCEPROP 1 LAST PATH I72
J 2
(-2873 3750);
DISPLAY 0.872340 (-2873 3750);
PAINT GREEN (-2873 3750);
DISPLAY INVISIBLE (-2873 3750);
FORCEADD TAP..1
R 2
(-2875 3600);
FORCEPROP 3 LASTPIN (-2825 3600) SIG_NAME M_C_CPU0_SB_CA<3>
J 0
(-2815 3610);
DISPLAY 0.659574 (-2815 3610);
PAINT MONO (-2815 3610);
DISPLAY INVISIBLE (-2815 3610);
FORCEPROP 1 LASTPIN (-2825 3600) BN 3
J 2
(-2813 3608);
DISPLAY 0.680851 (-2813 3608);
PAINT GREEN (-2813 3608);
FORCEPROP 2 LAST CDS_LIB standard
J 0
(-2875 3600);
DISPLAY INVISIBLE (-2875 3600);
FORCEPROP 1 LAST BODY_TYPE PLUMBING
J 2
(-2875 3650);
DISPLAY 0.872340 (-2875 3650);
PAINT GREEN (-2875 3650);
DISPLAY INVISIBLE (-2875 3650);
FORCEPROP 1 LAST HDL_TAP TRUE
J 2
(-3200 3475);
DISPLAY 0.872340 (-3200 3475);
DISPLAY INVISIBLE (-3200 3475);
FORCEPROP 1 LAST PATH I73
J 2
(-2873 3600);
DISPLAY 0.872340 (-2873 3600);
PAINT GREEN (-2873 3600);
DISPLAY INVISIBLE (-2873 3600);
FORCEADD TAP..1
R 2
(-2875 3650);
FORCEPROP 3 LASTPIN (-2825 3650) SIG_NAME M_C_CPU0_SB_CA<4>
J 0
(-2815 3660);
DISPLAY 0.659574 (-2815 3660);
PAINT MONO (-2815 3660);
DISPLAY INVISIBLE (-2815 3660);
FORCEPROP 1 LASTPIN (-2825 3650) BN 4
J 2
(-2813 3658);
DISPLAY 0.680851 (-2813 3658);
PAINT GREEN (-2813 3658);
FORCEPROP 2 LAST CDS_LIB standard
J 0
(-2875 3650);
DISPLAY INVISIBLE (-2875 3650);
FORCEPROP 1 LAST BODY_TYPE PLUMBING
J 2
(-2875 3700);
DISPLAY 0.872340 (-2875 3700);
PAINT GREEN (-2875 3700);
DISPLAY INVISIBLE (-2875 3700);
FORCEPROP 1 LAST HDL_TAP TRUE
J 2
(-3200 3525);
DISPLAY 0.872340 (-3200 3525);
DISPLAY INVISIBLE (-3200 3525);
FORCEPROP 1 LAST PATH I74
J 2
(-2873 3650);
DISPLAY 0.872340 (-2873 3650);
PAINT GREEN (-2873 3650);
DISPLAY INVISIBLE (-2873 3650);
FORCEADD TAP..1
R 2
(-2875 3900);
FORCEPROP 3 LASTPIN (-2825 3900) SIG_NAME M_C_CPU0_SA_CA<1>
J 0
(-2815 3910);
DISPLAY 0.659574 (-2815 3910);
PAINT MONO (-2815 3910);
DISPLAY INVISIBLE (-2815 3910);
FORCEPROP 1 LASTPIN (-2825 3900) BN 1
J 2
(-2813 3908);
DISPLAY 0.680851 (-2813 3908);
PAINT GREEN (-2813 3908);
FORCEPROP 2 LAST CDS_LIB standard
J 0
(-2875 3900);
DISPLAY INVISIBLE (-2875 3900);
FORCEPROP 1 LAST BODY_TYPE PLUMBING
J 2
(-2875 3950);
DISPLAY 0.872340 (-2875 3950);
PAINT GREEN (-2875 3950);
DISPLAY INVISIBLE (-2875 3950);
FORCEPROP 1 LAST HDL_TAP TRUE
J 2
(-3200 3775);
DISPLAY 0.872340 (-3200 3775);
DISPLAY INVISIBLE (-3200 3775);
FORCEPROP 1 LAST PATH I75
J 2
(-2873 3900);
DISPLAY 0.872340 (-2873 3900);
PAINT GREEN (-2873 3900);
DISPLAY INVISIBLE (-2873 3900);
FORCEADD TAP..1
R 2
(-2875 3850);
FORCEPROP 3 LASTPIN (-2825 3850) SIG_NAME M_C_CPU0_SA_CA<0>
J 0
(-2815 3860);
DISPLAY 0.659574 (-2815 3860);
PAINT MONO (-2815 3860);
DISPLAY INVISIBLE (-2815 3860);
FORCEPROP 1 LASTPIN (-2825 3850) BN 0
J 2
(-2813 3858);
DISPLAY 0.680851 (-2813 3858);
PAINT GREEN (-2813 3858);
FORCEPROP 2 LAST CDS_LIB standard
J 0
(-2875 3850);
DISPLAY INVISIBLE (-2875 3850);
FORCEPROP 1 LAST BODY_TYPE PLUMBING
J 2
(-2875 3900);
DISPLAY 0.872340 (-2875 3900);
PAINT GREEN (-2875 3900);
DISPLAY INVISIBLE (-2875 3900);
FORCEPROP 1 LAST HDL_TAP TRUE
J 2
(-3200 3725);
DISPLAY 0.872340 (-3200 3725);
DISPLAY INVISIBLE (-3200 3725);
FORCEPROP 1 LAST PATH I76
J 2
(-2873 3850);
DISPLAY 0.872340 (-2873 3850);
PAINT GREEN (-2873 3850);
DISPLAY INVISIBLE (-2873 3850);
FORCEADD TAP..1
R 2
(-2875 4050);
FORCEPROP 3 LASTPIN (-2825 4050) SIG_NAME M_C_CPU0_SA_CA<4>
J 0
(-2815 4060);
DISPLAY 0.659574 (-2815 4060);
PAINT MONO (-2815 4060);
DISPLAY INVISIBLE (-2815 4060);
FORCEPROP 1 LASTPIN (-2825 4050) BN 4
J 2
(-2813 4058);
DISPLAY 0.680851 (-2813 4058);
PAINT GREEN (-2813 4058);
FORCEPROP 2 LAST CDS_LIB standard
J 0
(-2875 4050);
DISPLAY INVISIBLE (-2875 4050);
FORCEPROP 1 LAST BODY_TYPE PLUMBING
J 2
(-2875 4100);
DISPLAY 0.872340 (-2875 4100);
PAINT GREEN (-2875 4100);
DISPLAY INVISIBLE (-2875 4100);
FORCEPROP 1 LAST HDL_TAP TRUE
J 2
(-3200 3925);
DISPLAY 0.872340 (-3200 3925);
DISPLAY INVISIBLE (-3200 3925);
FORCEPROP 1 LAST PATH I77
J 2
(-2873 4050);
DISPLAY 0.872340 (-2873 4050);
PAINT GREEN (-2873 4050);
DISPLAY INVISIBLE (-2873 4050);
FORCEADD TAP..1
R 2
(-2875 4000);
FORCEPROP 3 LASTPIN (-2825 4000) SIG_NAME M_C_CPU0_SA_CA<3>
J 0
(-2815 4010);
DISPLAY 0.659574 (-2815 4010);
PAINT MONO (-2815 4010);
DISPLAY INVISIBLE (-2815 4010);
FORCEPROP 1 LASTPIN (-2825 4000) BN 3
J 2
(-2813 4008);
DISPLAY 0.680851 (-2813 4008);
PAINT GREEN (-2813 4008);
FORCEPROP 2 LAST CDS_LIB standard
J 0
(-2875 4000);
DISPLAY INVISIBLE (-2875 4000);
FORCEPROP 1 LAST BODY_TYPE PLUMBING
J 2
(-2875 4050);
DISPLAY 0.872340 (-2875 4050);
PAINT GREEN (-2875 4050);
DISPLAY INVISIBLE (-2875 4050);
FORCEPROP 1 LAST HDL_TAP TRUE
J 2
(-3200 3875);
DISPLAY 0.872340 (-3200 3875);
DISPLAY INVISIBLE (-3200 3875);
FORCEPROP 1 LAST PATH I78
J 2
(-2873 4000);
DISPLAY 0.872340 (-2873 4000);
PAINT GREEN (-2873 4000);
DISPLAY INVISIBLE (-2873 4000);
FORCEADD TAP..1
R 2
(-2875 3950);
FORCEPROP 3 LASTPIN (-2825 3950) SIG_NAME M_C_CPU0_SA_CA<2>
J 0
(-2815 3960);
DISPLAY 0.659574 (-2815 3960);
PAINT MONO (-2815 3960);
DISPLAY INVISIBLE (-2815 3960);
FORCEPROP 1 LASTPIN (-2825 3950) BN 2
J 2
(-2813 3958);
DISPLAY 0.680851 (-2813 3958);
PAINT GREEN (-2813 3958);
FORCEPROP 2 LAST CDS_LIB standard
J 0
(-2875 3950);
DISPLAY INVISIBLE (-2875 3950);
FORCEPROP 1 LAST BODY_TYPE PLUMBING
J 2
(-2875 4000);
DISPLAY 0.872340 (-2875 4000);
PAINT GREEN (-2875 4000);
DISPLAY INVISIBLE (-2875 4000);
FORCEPROP 1 LAST HDL_TAP TRUE
J 2
(-3200 3825);
DISPLAY 0.872340 (-3200 3825);
DISPLAY INVISIBLE (-3200 3825);
FORCEPROP 1 LAST PATH I79
J 2
(-2873 3950);
DISPLAY 0.872340 (-2873 3950);
PAINT GREEN (-2873 3950);
DISPLAY INVISIBLE (-2873 3950);
FORCEADD OFFPAGE..1
(-3725 1650);
FORCEPROP 2 LAST $XR0 86 
J 0
(-4186 1650);
DISPLAY 0.638298 (-4186 1650);
PAINT MONO (-4186 1650);
FORCEPROP 2 LAST CDS_LIB standard
J 0
(-3725 1650);
PAINT MONO (-3725 1650);
DISPLAY INVISIBLE (-3725 1650);
FORCEPROP 1 LAST OFFPAGE TRUE
J 0
(-3400 1525);
DISPLAY 0.872340 (-3400 1525);
DISPLAY INVISIBLE (-3400 1525);
FORCEPROP 1 LAST COMMENT_BODY TRUE
J 0
(-3600 1550);
DISPLAY 0.872340 (-3600 1550);
PAINT GREEN (-3600 1550);
DISPLAY INVISIBLE (-3600 1550);
FORCEPROP 2 LAST PATH I8
J 0
(-3675 1725);
DISPLAY 1.021277 (-3675 1725);
DISPLAY INVISIBLE (-3675 1725);
FORCEADD TAP..1
R 2
(-2875 4100);
FORCEPROP 3 LASTPIN (-2825 4100) SIG_NAME M_C_CPU0_SA_CA<5>
J 0
(-2815 4110);
DISPLAY 0.659574 (-2815 4110);
PAINT MONO (-2815 4110);
DISPLAY INVISIBLE (-2815 4110);
FORCEPROP 1 LASTPIN (-2825 4100) BN 5
J 2
(-2813 4108);
DISPLAY 0.680851 (-2813 4108);
PAINT GREEN (-2813 4108);
FORCEPROP 2 LAST CDS_LIB standard
J 0
(-2875 4100);
DISPLAY INVISIBLE (-2875 4100);
FORCEPROP 1 LAST BODY_TYPE PLUMBING
J 2
(-2875 4150);
DISPLAY 0.872340 (-2875 4150);
PAINT GREEN (-2875 4150);
DISPLAY INVISIBLE (-2875 4150);
FORCEPROP 1 LAST HDL_TAP TRUE
J 2
(-3200 3975);
DISPLAY 0.872340 (-3200 3975);
DISPLAY INVISIBLE (-3200 3975);
FORCEPROP 1 LAST PATH I80
J 2
(-2873 4100);
DISPLAY 0.872340 (-2873 4100);
PAINT GREEN (-2873 4100);
DISPLAY INVISIBLE (-2873 4100);
FORCEADD TAP..1
R 2
(-2875 4150);
FORCEPROP 3 LASTPIN (-2825 4150) SIG_NAME M_C_CPU0_SA_CA<6>
J 0
(-2815 4160);
DISPLAY 0.659574 (-2815 4160);
PAINT MONO (-2815 4160);
DISPLAY INVISIBLE (-2815 4160);
FORCEPROP 1 LASTPIN (-2825 4150) BN 6
J 2
(-2813 4158);
DISPLAY 0.680851 (-2813 4158);
PAINT GREEN (-2813 4158);
FORCEPROP 2 LAST CDS_LIB standard
J 0
(-2875 4150);
DISPLAY INVISIBLE (-2875 4150);
FORCEPROP 1 LAST BODY_TYPE PLUMBING
J 2
(-2875 4200);
DISPLAY 0.872340 (-2875 4200);
PAINT GREEN (-2875 4200);
DISPLAY INVISIBLE (-2875 4200);
FORCEPROP 1 LAST HDL_TAP TRUE
J 2
(-3200 4025);
DISPLAY 0.872340 (-3200 4025);
DISPLAY INVISIBLE (-3200 4025);
FORCEPROP 1 LAST PATH I81
J 2
(-2873 4150);
DISPLAY 0.872340 (-2873 4150);
PAINT GREEN (-2873 4150);
DISPLAY INVISIBLE (-2873 4150);
FORCEADD TAP..1
(-1225 2300);
FORCEPROP 3 LASTPIN (-1275 2300) SIG_NAME M_C_CPU0_SB_DQ<27>
J 0
(-1265 2310);
DISPLAY 0.659574 (-1265 2310);
PAINT MONO (-1265 2310);
DISPLAY INVISIBLE (-1265 2310);
FORCEPROP 1 LASTPIN (-1275 2300) BN 27
J 0
(-1287 2308);
DISPLAY 0.680851 (-1287 2308);
PAINT GREEN (-1287 2308);
FORCEPROP 2 LAST CDS_LIB standard
J 0
(-1225 2300);
DISPLAY INVISIBLE (-1225 2300);
FORCEPROP 1 LAST BODY_TYPE PLUMBING
J 0
(-1225 2350);
DISPLAY 0.872340 (-1225 2350);
PAINT GREEN (-1225 2350);
DISPLAY INVISIBLE (-1225 2350);
FORCEPROP 1 LAST HDL_TAP TRUE
J 0
(-900 2175);
DISPLAY 0.872340 (-900 2175);
DISPLAY INVISIBLE (-900 2175);
FORCEPROP 1 LAST PATH I82
J 0
(-1227 2300);
DISPLAY 0.872340 (-1227 2300);
PAINT GREEN (-1227 2300);
DISPLAY INVISIBLE (-1227 2300);
FORCEADD TAP..1
(-1225 2350);
FORCEPROP 3 LASTPIN (-1275 2350) SIG_NAME M_C_CPU0_SB_DQ<28>
J 0
(-1265 2360);
DISPLAY 0.659574 (-1265 2360);
PAINT MONO (-1265 2360);
DISPLAY INVISIBLE (-1265 2360);
FORCEPROP 1 LASTPIN (-1275 2350) BN 28
J 0
(-1287 2358);
DISPLAY 0.680851 (-1287 2358);
PAINT GREEN (-1287 2358);
FORCEPROP 2 LAST CDS_LIB standard
J 0
(-1225 2350);
DISPLAY INVISIBLE (-1225 2350);
FORCEPROP 1 LAST BODY_TYPE PLUMBING
J 0
(-1225 2400);
DISPLAY 0.872340 (-1225 2400);
PAINT GREEN (-1225 2400);
DISPLAY INVISIBLE (-1225 2400);
FORCEPROP 1 LAST HDL_TAP TRUE
J 0
(-900 2225);
DISPLAY 0.872340 (-900 2225);
DISPLAY INVISIBLE (-900 2225);
FORCEPROP 1 LAST PATH I83
J 0
(-1227 2350);
DISPLAY 0.872340 (-1227 2350);
PAINT GREEN (-1227 2350);
DISPLAY INVISIBLE (-1227 2350);
FORCEADD TAP..1
(-1225 2400);
FORCEPROP 3 LASTPIN (-1275 2400) SIG_NAME M_C_CPU0_SB_DQ<29>
J 0
(-1265 2410);
DISPLAY 0.659574 (-1265 2410);
PAINT MONO (-1265 2410);
DISPLAY INVISIBLE (-1265 2410);
FORCEPROP 1 LASTPIN (-1275 2400) BN 29
J 0
(-1287 2408);
DISPLAY 0.680851 (-1287 2408);
PAINT GREEN (-1287 2408);
FORCEPROP 2 LAST CDS_LIB standard
J 0
(-1225 2400);
DISPLAY INVISIBLE (-1225 2400);
FORCEPROP 1 LAST BODY_TYPE PLUMBING
J 0
(-1225 2450);
DISPLAY 0.872340 (-1225 2450);
PAINT GREEN (-1225 2450);
DISPLAY INVISIBLE (-1225 2450);
FORCEPROP 1 LAST HDL_TAP TRUE
J 0
(-900 2275);
DISPLAY 0.872340 (-900 2275);
DISPLAY INVISIBLE (-900 2275);
FORCEPROP 1 LAST PATH I84
J 0
(-1227 2400);
DISPLAY 0.872340 (-1227 2400);
PAINT GREEN (-1227 2400);
DISPLAY INVISIBLE (-1227 2400);
FORCEADD TAP..1
(-1225 2500);
FORCEPROP 3 LASTPIN (-1275 2500) SIG_NAME M_C_CPU0_SB_DQ<31>
J 0
(-1265 2510);
DISPLAY 0.659574 (-1265 2510);
PAINT MONO (-1265 2510);
DISPLAY INVISIBLE (-1265 2510);
FORCEPROP 1 LASTPIN (-1275 2500) BN 31
J 0
(-1287 2508);
DISPLAY 0.680851 (-1287 2508);
PAINT GREEN (-1287 2508);
FORCEPROP 2 LAST CDS_LIB standard
J 0
(-1225 2500);
DISPLAY INVISIBLE (-1225 2500);
FORCEPROP 1 LAST BODY_TYPE PLUMBING
J 0
(-1225 2550);
DISPLAY 0.872340 (-1225 2550);
PAINT GREEN (-1225 2550);
DISPLAY INVISIBLE (-1225 2550);
FORCEPROP 1 LAST HDL_TAP TRUE
J 0
(-900 2375);
DISPLAY 0.872340 (-900 2375);
DISPLAY INVISIBLE (-900 2375);
FORCEPROP 1 LAST PATH I85
J 0
(-1227 2500);
DISPLAY 0.872340 (-1227 2500);
PAINT GREEN (-1227 2500);
DISPLAY INVISIBLE (-1227 2500);
FORCEADD TAP..1
(-1225 2450);
FORCEPROP 3 LASTPIN (-1275 2450) SIG_NAME M_C_CPU0_SB_DQ<30>
J 0
(-1265 2460);
DISPLAY 0.659574 (-1265 2460);
PAINT MONO (-1265 2460);
DISPLAY INVISIBLE (-1265 2460);
FORCEPROP 1 LASTPIN (-1275 2450) BN 30
J 0
(-1287 2458);
DISPLAY 0.680851 (-1287 2458);
PAINT GREEN (-1287 2458);
FORCEPROP 2 LAST CDS_LIB standard
J 0
(-1225 2450);
DISPLAY INVISIBLE (-1225 2450);
FORCEPROP 1 LAST BODY_TYPE PLUMBING
J 0
(-1225 2500);
DISPLAY 0.872340 (-1225 2500);
PAINT GREEN (-1225 2500);
DISPLAY INVISIBLE (-1225 2500);
FORCEPROP 1 LAST HDL_TAP TRUE
J 0
(-900 2325);
DISPLAY 0.872340 (-900 2325);
DISPLAY INVISIBLE (-900 2325);
FORCEPROP 1 LAST PATH I86
J 0
(-1227 2450);
DISPLAY 0.872340 (-1227 2450);
PAINT GREEN (-1227 2450);
DISPLAY INVISIBLE (-1227 2450);
FORCEADD TAP..1
(-1225 2600);
FORCEPROP 3 LASTPIN (-1275 2600) SIG_NAME M_C_CPU0_SA_DQ<0>
J 0
(-1265 2610);
DISPLAY 0.659574 (-1265 2610);
PAINT MONO (-1265 2610);
DISPLAY INVISIBLE (-1265 2610);
FORCEPROP 1 LASTPIN (-1275 2600) BN 0
J 0
(-1287 2608);
DISPLAY 0.680851 (-1287 2608);
PAINT GREEN (-1287 2608);
FORCEPROP 2 LAST CDS_LIB standard
J 0
(-1225 2600);
PAINT MONO (-1225 2600);
DISPLAY INVISIBLE (-1225 2600);
FORCEPROP 1 LAST BODY_TYPE PLUMBING
J 0
(-1225 2650);
DISPLAY 0.872340 (-1225 2650);
PAINT GREEN (-1225 2650);
DISPLAY INVISIBLE (-1225 2650);
FORCEPROP 1 LAST HDL_TAP TRUE
J 0
(-900 2475);
DISPLAY 0.872340 (-900 2475);
DISPLAY INVISIBLE (-900 2475);
FORCEPROP 1 LAST PATH I87
J 0
(-1227 2600);
DISPLAY 0.872340 (-1227 2600);
PAINT GREEN (-1227 2600);
DISPLAY INVISIBLE (-1227 2600);
FORCEADD TAP..1
(-1225 2650);
FORCEPROP 3 LASTPIN (-1275 2650) SIG_NAME M_C_CPU0_SA_DQ<1>
J 0
(-1265 2660);
DISPLAY 0.659574 (-1265 2660);
PAINT MONO (-1265 2660);
DISPLAY INVISIBLE (-1265 2660);
FORCEPROP 1 LASTPIN (-1275 2650) BN 1
J 0
(-1287 2658);
DISPLAY 0.680851 (-1287 2658);
PAINT GREEN (-1287 2658);
FORCEPROP 2 LAST CDS_LIB standard
J 0
(-1225 2650);
PAINT MONO (-1225 2650);
DISPLAY INVISIBLE (-1225 2650);
FORCEPROP 1 LAST BODY_TYPE PLUMBING
J 0
(-1225 2700);
DISPLAY 0.872340 (-1225 2700);
PAINT GREEN (-1225 2700);
DISPLAY INVISIBLE (-1225 2700);
FORCEPROP 1 LAST HDL_TAP TRUE
J 0
(-900 2525);
DISPLAY 0.872340 (-900 2525);
DISPLAY INVISIBLE (-900 2525);
FORCEPROP 1 LAST PATH I88
J 0
(-1227 2650);
DISPLAY 0.872340 (-1227 2650);
PAINT GREEN (-1227 2650);
DISPLAY INVISIBLE (-1227 2650);
FORCEADD TAP..1
(-1225 2800);
FORCEPROP 3 LASTPIN (-1275 2800) SIG_NAME M_C_CPU0_SA_DQ<4>
J 0
(-1265 2810);
DISPLAY 0.659574 (-1265 2810);
PAINT MONO (-1265 2810);
DISPLAY INVISIBLE (-1265 2810);
FORCEPROP 1 LASTPIN (-1275 2800) BN 4
J 0
(-1287 2808);
DISPLAY 0.680851 (-1287 2808);
PAINT GREEN (-1287 2808);
FORCEPROP 2 LAST CDS_LIB standard
J 0
(-1225 2800);
PAINT MONO (-1225 2800);
DISPLAY INVISIBLE (-1225 2800);
FORCEPROP 1 LAST BODY_TYPE PLUMBING
J 0
(-1225 2850);
DISPLAY 0.872340 (-1225 2850);
PAINT GREEN (-1225 2850);
DISPLAY INVISIBLE (-1225 2850);
FORCEPROP 1 LAST HDL_TAP TRUE
J 0
(-900 2675);
DISPLAY 0.872340 (-900 2675);
DISPLAY INVISIBLE (-900 2675);
FORCEPROP 1 LAST PATH I89
J 0
(-1227 2800);
DISPLAY 0.872340 (-1227 2800);
PAINT GREEN (-1227 2800);
DISPLAY INVISIBLE (-1227 2800);
FORCEADD OFFPAGE..1
(-3800 1800);
FORCEPROP 2 LAST $XR1 87 
J 0
(-4111 1800);
DISPLAY 0.638298 (-4111 1800);
PAINT MONO (-4111 1800);
FORCEPROP 2 LAST $XR0 22 
J 0
(-4021 1800);
DISPLAY 0.638298 (-4021 1800);
PAINT MONO (-4021 1800);
FORCEPROP 2 LAST CDS_LIB standard
J 0
(-3800 1800);
PAINT MONO (-3800 1800);
DISPLAY INVISIBLE (-3800 1800);
FORCEPROP 1 LAST OFFPAGE TRUE
J 0
(-3475 1675);
DISPLAY 0.872340 (-3475 1675);
DISPLAY INVISIBLE (-3475 1675);
FORCEPROP 1 LAST COMMENT_BODY TRUE
J 0
(-3675 1700);
DISPLAY 0.872340 (-3675 1700);
PAINT GREEN (-3675 1700);
DISPLAY INVISIBLE (-3675 1700);
FORCEPROP 2 LAST PATH I9
J 0
(-3750 1875);
DISPLAY 1.021277 (-3750 1875);
DISPLAY INVISIBLE (-3750 1875);
FORCEADD TAP..1
(-1225 2750);
FORCEPROP 3 LASTPIN (-1275 2750) SIG_NAME M_C_CPU0_SA_DQ<3>
J 0
(-1265 2760);
DISPLAY 0.659574 (-1265 2760);
PAINT MONO (-1265 2760);
DISPLAY INVISIBLE (-1265 2760);
FORCEPROP 1 LASTPIN (-1275 2750) BN 3
J 0
(-1287 2758);
DISPLAY 0.680851 (-1287 2758);
PAINT GREEN (-1287 2758);
FORCEPROP 2 LAST CDS_LIB standard
J 0
(-1225 2750);
PAINT MONO (-1225 2750);
DISPLAY INVISIBLE (-1225 2750);
FORCEPROP 1 LAST BODY_TYPE PLUMBING
J 0
(-1225 2800);
DISPLAY 0.872340 (-1225 2800);
PAINT GREEN (-1225 2800);
DISPLAY INVISIBLE (-1225 2800);
FORCEPROP 1 LAST HDL_TAP TRUE
J 0
(-900 2625);
DISPLAY 0.872340 (-900 2625);
DISPLAY INVISIBLE (-900 2625);
FORCEPROP 1 LAST PATH I90
J 0
(-1227 2750);
DISPLAY 0.872340 (-1227 2750);
PAINT GREEN (-1227 2750);
DISPLAY INVISIBLE (-1227 2750);
FORCEADD TAP..1
(-1225 2700);
FORCEPROP 3 LASTPIN (-1275 2700) SIG_NAME M_C_CPU0_SA_DQ<2>
J 0
(-1265 2710);
DISPLAY 0.659574 (-1265 2710);
PAINT MONO (-1265 2710);
DISPLAY INVISIBLE (-1265 2710);
FORCEPROP 1 LASTPIN (-1275 2700) BN 2
J 0
(-1287 2708);
DISPLAY 0.680851 (-1287 2708);
PAINT GREEN (-1287 2708);
FORCEPROP 2 LAST CDS_LIB standard
J 0
(-1225 2700);
PAINT MONO (-1225 2700);
DISPLAY INVISIBLE (-1225 2700);
FORCEPROP 1 LAST BODY_TYPE PLUMBING
J 0
(-1225 2750);
DISPLAY 0.872340 (-1225 2750);
PAINT GREEN (-1225 2750);
DISPLAY INVISIBLE (-1225 2750);
FORCEPROP 1 LAST HDL_TAP TRUE
J 0
(-900 2575);
DISPLAY 0.872340 (-900 2575);
DISPLAY INVISIBLE (-900 2575);
FORCEPROP 1 LAST PATH I91
J 0
(-1227 2700);
DISPLAY 0.872340 (-1227 2700);
PAINT GREEN (-1227 2700);
DISPLAY INVISIBLE (-1227 2700);
FORCEADD TAP..1
(-1225 2850);
FORCEPROP 3 LASTPIN (-1275 2850) SIG_NAME M_C_CPU0_SA_DQ<5>
J 0
(-1265 2860);
DISPLAY 0.659574 (-1265 2860);
PAINT MONO (-1265 2860);
DISPLAY INVISIBLE (-1265 2860);
FORCEPROP 1 LASTPIN (-1275 2850) BN 5
J 0
(-1287 2858);
DISPLAY 0.680851 (-1287 2858);
PAINT GREEN (-1287 2858);
FORCEPROP 2 LAST CDS_LIB standard
J 0
(-1225 2850);
PAINT MONO (-1225 2850);
DISPLAY INVISIBLE (-1225 2850);
FORCEPROP 1 LAST BODY_TYPE PLUMBING
J 0
(-1225 2900);
DISPLAY 0.872340 (-1225 2900);
PAINT GREEN (-1225 2900);
DISPLAY INVISIBLE (-1225 2900);
FORCEPROP 1 LAST HDL_TAP TRUE
J 0
(-900 2725);
DISPLAY 0.872340 (-900 2725);
DISPLAY INVISIBLE (-900 2725);
FORCEPROP 1 LAST PATH I92
J 0
(-1227 2850);
DISPLAY 0.872340 (-1227 2850);
PAINT GREEN (-1227 2850);
DISPLAY INVISIBLE (-1227 2850);
FORCEADD TAP..1
(-1225 2900);
FORCEPROP 3 LASTPIN (-1275 2900) SIG_NAME M_C_CPU0_SA_DQ<6>
J 0
(-1265 2910);
DISPLAY 0.659574 (-1265 2910);
PAINT MONO (-1265 2910);
DISPLAY INVISIBLE (-1265 2910);
FORCEPROP 1 LASTPIN (-1275 2900) BN 6
J 0
(-1287 2908);
DISPLAY 0.680851 (-1287 2908);
PAINT GREEN (-1287 2908);
FORCEPROP 2 LAST CDS_LIB standard
J 0
(-1225 2900);
PAINT MONO (-1225 2900);
DISPLAY INVISIBLE (-1225 2900);
FORCEPROP 1 LAST BODY_TYPE PLUMBING
J 0
(-1225 2950);
DISPLAY 0.872340 (-1225 2950);
PAINT GREEN (-1225 2950);
DISPLAY INVISIBLE (-1225 2950);
FORCEPROP 1 LAST HDL_TAP TRUE
J 0
(-900 2775);
DISPLAY 0.872340 (-900 2775);
DISPLAY INVISIBLE (-900 2775);
FORCEPROP 1 LAST PATH I93
J 0
(-1227 2900);
DISPLAY 0.872340 (-1227 2900);
PAINT GREEN (-1227 2900);
DISPLAY INVISIBLE (-1227 2900);
FORCEADD TAP..1
(-1225 3050);
FORCEPROP 3 LASTPIN (-1275 3050) SIG_NAME M_C_CPU0_SA_DQ<9>
J 0
(-1265 3060);
DISPLAY 0.659574 (-1265 3060);
PAINT MONO (-1265 3060);
DISPLAY INVISIBLE (-1265 3060);
FORCEPROP 1 LASTPIN (-1275 3050) BN 9
J 0
(-1287 3058);
DISPLAY 0.680851 (-1287 3058);
PAINT GREEN (-1287 3058);
FORCEPROP 2 LAST CDS_LIB standard
J 0
(-1225 3050);
PAINT MONO (-1225 3050);
DISPLAY INVISIBLE (-1225 3050);
FORCEPROP 1 LAST BODY_TYPE PLUMBING
J 0
(-1225 3100);
DISPLAY 0.872340 (-1225 3100);
PAINT GREEN (-1225 3100);
DISPLAY INVISIBLE (-1225 3100);
FORCEPROP 1 LAST HDL_TAP TRUE
J 0
(-900 2925);
DISPLAY 0.872340 (-900 2925);
DISPLAY INVISIBLE (-900 2925);
FORCEPROP 1 LAST PATH I94
J 0
(-1227 3050);
DISPLAY 0.872340 (-1227 3050);
PAINT GREEN (-1227 3050);
DISPLAY INVISIBLE (-1227 3050);
FORCEADD TAP..1
(-1225 2950);
FORCEPROP 3 LASTPIN (-1275 2950) SIG_NAME M_C_CPU0_SA_DQ<7>
J 0
(-1265 2960);
DISPLAY 0.659574 (-1265 2960);
PAINT MONO (-1265 2960);
DISPLAY INVISIBLE (-1265 2960);
FORCEPROP 1 LASTPIN (-1275 2950) BN 7
J 0
(-1287 2958);
DISPLAY 0.680851 (-1287 2958);
PAINT GREEN (-1287 2958);
FORCEPROP 2 LAST CDS_LIB standard
J 0
(-1225 2950);
PAINT MONO (-1225 2950);
DISPLAY INVISIBLE (-1225 2950);
FORCEPROP 1 LAST BODY_TYPE PLUMBING
J 0
(-1225 3000);
DISPLAY 0.872340 (-1225 3000);
PAINT GREEN (-1225 3000);
DISPLAY INVISIBLE (-1225 3000);
FORCEPROP 1 LAST HDL_TAP TRUE
J 0
(-900 2825);
DISPLAY 0.872340 (-900 2825);
DISPLAY INVISIBLE (-900 2825);
FORCEPROP 1 LAST PATH I95
J 0
(-1227 2950);
DISPLAY 0.872340 (-1227 2950);
PAINT GREEN (-1227 2950);
DISPLAY INVISIBLE (-1227 2950);
FORCEADD TAP..1
(-1225 3000);
FORCEPROP 3 LASTPIN (-1275 3000) SIG_NAME M_C_CPU0_SA_DQ<8>
J 0
(-1265 3010);
DISPLAY 0.659574 (-1265 3010);
PAINT MONO (-1265 3010);
DISPLAY INVISIBLE (-1265 3010);
FORCEPROP 1 LASTPIN (-1275 3000) BN 8
J 0
(-1287 3008);
DISPLAY 0.680851 (-1287 3008);
PAINT GREEN (-1287 3008);
FORCEPROP 2 LAST CDS_LIB standard
J 0
(-1225 3000);
PAINT MONO (-1225 3000);
DISPLAY INVISIBLE (-1225 3000);
FORCEPROP 1 LAST BODY_TYPE PLUMBING
J 0
(-1225 3050);
DISPLAY 0.872340 (-1225 3050);
PAINT GREEN (-1225 3050);
DISPLAY INVISIBLE (-1225 3050);
FORCEPROP 1 LAST HDL_TAP TRUE
J 0
(-900 2875);
DISPLAY 0.872340 (-900 2875);
DISPLAY INVISIBLE (-900 2875);
FORCEPROP 1 LAST PATH I96
J 0
(-1227 3000);
DISPLAY 0.872340 (-1227 3000);
PAINT GREEN (-1227 3000);
DISPLAY INVISIBLE (-1227 3000);
FORCEADD TAP..1
(-1225 3100);
FORCEPROP 3 LASTPIN (-1275 3100) SIG_NAME M_C_CPU0_SA_DQ<10>
J 0
(-1265 3110);
DISPLAY 0.659574 (-1265 3110);
PAINT MONO (-1265 3110);
DISPLAY INVISIBLE (-1265 3110);
FORCEPROP 1 LASTPIN (-1275 3100) BN 10
J 0
(-1287 3108);
DISPLAY 0.680851 (-1287 3108);
PAINT GREEN (-1287 3108);
FORCEPROP 2 LAST CDS_LIB standard
J 0
(-1225 3100);
PAINT MONO (-1225 3100);
DISPLAY INVISIBLE (-1225 3100);
FORCEPROP 1 LAST BODY_TYPE PLUMBING
J 0
(-1225 3150);
DISPLAY 0.872340 (-1225 3150);
PAINT GREEN (-1225 3150);
DISPLAY INVISIBLE (-1225 3150);
FORCEPROP 1 LAST HDL_TAP TRUE
J 0
(-900 2975);
DISPLAY 0.872340 (-900 2975);
DISPLAY INVISIBLE (-900 2975);
FORCEPROP 1 LAST PATH I97
J 0
(-1227 3100);
DISPLAY 0.872340 (-1227 3100);
PAINT GREEN (-1227 3100);
DISPLAY INVISIBLE (-1227 3100);
FORCEADD TAP..1
(-1225 3150);
FORCEPROP 3 LASTPIN (-1275 3150) SIG_NAME M_C_CPU0_SA_DQ<11>
J 0
(-1265 3160);
DISPLAY 0.659574 (-1265 3160);
PAINT MONO (-1265 3160);
DISPLAY INVISIBLE (-1265 3160);
FORCEPROP 1 LASTPIN (-1275 3150) BN 11
J 0
(-1287 3158);
DISPLAY 0.680851 (-1287 3158);
PAINT GREEN (-1287 3158);
FORCEPROP 2 LAST CDS_LIB standard
J 0
(-1225 3150);
PAINT MONO (-1225 3150);
DISPLAY INVISIBLE (-1225 3150);
FORCEPROP 1 LAST BODY_TYPE PLUMBING
J 0
(-1225 3200);
DISPLAY 0.872340 (-1225 3200);
PAINT GREEN (-1225 3200);
DISPLAY INVISIBLE (-1225 3200);
FORCEPROP 1 LAST HDL_TAP TRUE
J 0
(-900 3025);
DISPLAY 0.872340 (-900 3025);
DISPLAY INVISIBLE (-900 3025);
FORCEPROP 1 LAST PATH I98
J 0
(-1227 3150);
DISPLAY 0.872340 (-1227 3150);
PAINT GREEN (-1227 3150);
DISPLAY INVISIBLE (-1227 3150);
FORCEADD TAP..1
(-1225 3250);
FORCEPROP 3 LASTPIN (-1275 3250) SIG_NAME M_C_CPU0_SA_DQ<13>
J 0
(-1265 3260);
DISPLAY 0.659574 (-1265 3260);
PAINT MONO (-1265 3260);
DISPLAY INVISIBLE (-1265 3260);
FORCEPROP 1 LASTPIN (-1275 3250) BN 13
J 0
(-1287 3258);
DISPLAY 0.680851 (-1287 3258);
PAINT GREEN (-1287 3258);
FORCEPROP 2 LAST CDS_LIB standard
J 0
(-1225 3250);
PAINT MONO (-1225 3250);
DISPLAY INVISIBLE (-1225 3250);
FORCEPROP 1 LAST BODY_TYPE PLUMBING
J 0
(-1225 3300);
DISPLAY 0.872340 (-1225 3300);
PAINT GREEN (-1225 3300);
DISPLAY INVISIBLE (-1225 3300);
FORCEPROP 1 LAST HDL_TAP TRUE
J 0
(-900 3125);
DISPLAY 0.872340 (-900 3125);
DISPLAY INVISIBLE (-900 3125);
FORCEPROP 1 LAST PATH I99
J 0
(-1227 3250);
DISPLAY 0.872340 (-1227 3250);
PAINT GREEN (-1227 3250);
DISPLAY INVISIBLE (-1227 3250);
FORCEADD CAD_NOTE..1
(625 -300);
FORCEPROP 0 LAST S1 PLACE THE BYPASS CAPS CLOSE TO DIMM
J 0
(500 -425);
DISPLAY 1.021277 (500 -425);
PAINT WHITE (500 -425);
FORCEPROP 2 LAST CDS_LIB logical_power
J 0
(625 -300);
PAINT MONO (625 -300);
DISPLAY INVISIBLE (625 -300);
FORCEPROP 1 LAST COMMENT_BODY TRUE
J 0
(650 -200);
DISPLAY 0.978723 (650 -200);
DISPLAY INVISIBLE (650 -200);
FORCEADD QUANTA_TITLE_BLOCK_C..1
(5100 -1600);
FORCEPROP 0 LAST CDS_CON_LAST_MODIFIED Fri Aug 25 14:01:05 2023
J 0
(3215 -1585);
PAINT MONO (3215 -1585);
DISPLAY INVISIBLE (3215 -1585);
FORCEPROP 1 LAST CUSTOM_TXT_CDS <CON_LAST_MODIFIED>
J 0
(3215 -1585);
DISPLAY 0.978723 (3215 -1585);
FORCEPROP 2 LAST CUSTOM_TXT_CDS <XR_PAGE_TITLE>
J 0
(-2790 3650);
DISPLAY 0.638298 (-2790 3650);
PAINT PINK (-2790 3650);
DISPLAY INVISIBLE (-2790 3650);
FORCEPROP 2 LAST CUSTOM_TXT_CDS <Q_NUMBER>
J 0
(3697 -1497);
DISPLAY 1.212766 (3697 -1497);
FORCEPROP 1 LAST CUSTOM_TXT_CDS <NAME_2>
J 0
(1925 -1550);
FORCEPROP 1 LAST CUSTOM_TXT_CDS <NAME_1>
J 0
(1925 -1425);
FORCEPROP 1 LAST CUSTOM_TXT_CDS <Q_PROJ>
J 0
(2718 -1498);
DISPLAY 1.212766 (2718 -1498);
FORCEPROP 1 LAST CUSTOM_TXT_CDS <Q_REV>
J 0
(4916 -1497);
DISPLAY 1.212766 (4916 -1497);
FORCEPROP 1 LAST CUSTOM_TXT_CDS <CON_PAGE_NUM> OF <CON_TOTAL_PAGES>
J 0
(4654 -1582);
DISPLAY 0.978723 (4654 -1582);
FORCEPROP 1 LAST Q_TITLE DDR5 - CPU0 CHC DIMM1(YELLOW)
J 0
(-4266 -1574);
DISPLAY 2.446809 (-4266 -1574);
PAINT GREEN (-4266 -1574);
FORCEPROP 1 LAST Q_DEPT 
J 1
(1337 -1551);
DISPLAY 1.957447 (1337 -1551);
PAINT GREEN (1337 -1551);
FORCEPROP 1 LAST COMMENT_BODY TRUE
J 0
(5112 -1613);
DISPLAY 0.978723 (5112 -1613);
PAINT GREEN (5112 -1613);
DISPLAY INVISIBLE (5112 -1613);
FORCEPROP 2 LAST CDS_XR_PAGE_TITLE CR-86 : @S9S_MB_2U_LIB.S9S_MB_2U(SCH_1):PAGE86
J 0
(-2790 3650);
DISPLAY 0.638298 (-2790 3650);
PAINT PINK (-2790 3650);
DISPLAY INVISIBLE (-2790 3650);
FORCEPROP 2 LAST PAGE_BORDER TRUE
J 0
(-2790 3650);
DISPLAY 0.638298 (-2790 3650);
PAINT PINK (-2790 3650);
DISPLAY INVISIBLE (-2790 3650);
FORCEPROP 1 LAST CDS_LMAN_SYM_OUTLINE -9475,6775,100,-125
J 0
(5100 -1600);
DISPLAY 0.468085 (5100 -1600);
PAINT GREEN (5100 -1600);
DISPLAY INVISIBLE (5100 -1600);
FORCEPROP 2 LAST CDS_LIB pure_quanta
J 0
(5100 -1600);
PAINT MONO (5100 -1600);
DISPLAY INVISIBLE (5100 -1600);
WIRE 17 -1 (-1175 4125)(-1175 4175);
WIRE 17 -1 (-1175 4075)(-1175 4125);
WIRE 17 -1 (-1175 4175)(-450 4175);
FORCEPROP 2 LAST SIG_NAME M_C_CPU0_SA_DQ<31:0>
J 0
(-1110 4185);
DISPLAY 0.680851 (-1110 4185);
PAINT WHITE (-1110 4185);
WIRE 17 -1 (-2925 2725)(-2925 2775);
WIRE 17 -1 (-2925 2675)(-2925 2725);
WIRE 17 -1 (-3750 2775)(-2925 2775);
FORCEPROP 2 LAST SIG_NAME M_C_CPU0_SA_CB<7:0>
J 0
(-3660 2785);
DISPLAY 0.680851 (-3660 2785);
PAINT WHITE (-3660 2785);
WIRE 17 -1 (-2925 2625)(-2925 2675);
WIRE 17 -1 (-2925 2575)(-2925 2625);
WIRE 17 -1 (-2925 2525)(-2925 2575);
WIRE 17 -1 (-2925 2475)(-2925 2525);
WIRE 17 -1 (-2925 2425)(-2925 2475);
WIRE 17 -1 (-2925 2275)(-2925 2325);
WIRE 17 -1 (-2925 2225)(-2925 2275);
WIRE 17 -1 (-3750 2325)(-2925 2325);
FORCEPROP 2 LAST SIG_NAME M_C_CPU0_SB_CB<7:0>
J 0
(-3660 2335);
DISPLAY 0.680851 (-3660 2335);
PAINT WHITE (-3660 2335);
WIRE 17 -1 (-2925 3875)(-2925 3925);
WIRE 17 -1 (-2925 3925)(-2925 3975);
WIRE 17 -1 (-2925 3975)(-2925 4025);
WIRE 17 -1 (-2925 4025)(-2925 4075);
WIRE 17 -1 (-2925 4075)(-2925 4125);
WIRE 17 -1 (-2925 4125)(-2925 4175);
WIRE 17 -1 (-3750 4175)(-2925 4175);
FORCEPROP 2 LAST SIG_NAME M_C_CPU0_SA_CA<6:0>
J 0
(-3660 4185);
DISPLAY 0.680851 (-3660 4185);
PAINT WHITE (-3660 4185);
WIRE 17 -1 (-2925 3525)(-2925 3575);
WIRE 17 -1 (-2925 3475)(-2925 3525);
WIRE 17 -1 (-2925 3575)(-2925 3625);
WIRE 17 -1 (-2925 3625)(-2925 3675);
WIRE 17 -1 (-2925 3675)(-2925 3725);
WIRE 17 -1 (-2925 3725)(-2925 3775);
WIRE 17 -1 (-3750 3775)(-2925 3775);
FORCEPROP 2 LAST SIG_NAME M_C_CPU0_SB_CA<6:0>
J 0
(-3660 3785);
DISPLAY 0.680851 (-3660 3785);
PAINT WHITE (-3660 3785);
WIRE 17 -1 (-2925 2175)(-2925 2225);
WIRE 17 -1 (-2925 2125)(-2925 2175);
WIRE 17 -1 (-2925 2075)(-2925 2125);
WIRE 17 -1 (-2925 2025)(-2925 2075);
WIRE 17 -1 (-2925 1975)(-2925 2025);
WIRE 17 -1 (-1175 4025)(-1175 4075);
WIRE 17 -1 (-1175 3975)(-1175 4025);
WIRE 17 -1 (-1175 3925)(-1175 3975);
WIRE 17 -1 (-1175 3875)(-1175 3925);
WIRE 17 -1 (-1175 3825)(-1175 3875);
WIRE 17 -1 (-1175 3775)(-1175 3825);
WIRE 17 -1 (-1175 3725)(-1175 3775);
WIRE 17 -1 (-1175 3675)(-1175 3725);
WIRE 17 -1 (-1175 3625)(-1175 3675);
WIRE 17 -1 (-1175 3575)(-1175 3625);
WIRE 17 -1 (-1175 3525)(-1175 3575);
WIRE 17 -1 (-1175 3475)(-1175 3525);
WIRE 17 -1 (-1175 3425)(-1175 3475);
WIRE 17 -1 (-1175 3375)(-1175 3425);
WIRE 17 -1 (-1175 3325)(-1175 3375);
WIRE 17 -1 (-1175 3275)(-1175 3325);
WIRE 17 -1 (-1175 3225)(-1175 3275);
WIRE 17 -1 (-1175 3175)(-1175 3225);
WIRE 17 -1 (-1175 3125)(-1175 3175);
WIRE 17 -1 (-1175 3075)(-1175 3125);
WIRE 17 -1 (-1175 3025)(-1175 3075);
WIRE 17 -1 (-1175 2975)(-1175 3025);
WIRE 17 -1 (-1175 2925)(-1175 2975);
WIRE 17 -1 (-1175 2875)(-1175 2925);
WIRE 17 -1 (-1175 2825)(-1175 2875);
WIRE 17 -1 (-1175 2775)(-1175 2825);
WIRE 17 -1 (-1175 2725)(-1175 2775);
WIRE 17 -1 (-1175 2675)(-1175 2725);
WIRE 17 -1 (-1175 2625)(-1175 2675);
WIRE 17 -1 (-1175 2475)(-1175 2525);
WIRE 17 -1 (-1175 2425)(-1175 2475);
WIRE 17 -1 (-1175 2525)(-450 2525);
FORCEPROP 2 LAST SIG_NAME M_C_CPU0_SB_DQ<31:0>
J 0
(-1110 2535);
DISPLAY 0.680851 (-1110 2535);
PAINT WHITE (-1110 2535);
WIRE 17 -1 (-1175 2375)(-1175 2425);
WIRE 17 -1 (-1175 2325)(-1175 2375);
WIRE 17 -1 (-1175 2275)(-1175 2325);
WIRE 17 -1 (-1175 2225)(-1175 2275);
WIRE 17 -1 (-1175 2175)(-1175 2225);
WIRE 17 -1 (-1175 2125)(-1175 2175);
WIRE 17 -1 (-1175 2075)(-1175 2125);
WIRE 17 -1 (-1175 2025)(-1175 2075);
WIRE 17 -1 (-1175 1975)(-1175 2025);
WIRE 17 -1 (-1175 1925)(-1175 1975);
WIRE 17 -1 (-1175 1875)(-1175 1925);
WIRE 17 -1 (-1175 1825)(-1175 1875);
WIRE 17 -1 (-1175 1775)(-1175 1825);
WIRE 17 -1 (-1175 1725)(-1175 1775);
WIRE 17 -1 (-1175 1675)(-1175 1725);
WIRE 17 -1 (-1175 1625)(-1175 1675);
WIRE 17 -1 (-1175 1575)(-1175 1625);
WIRE 17 -1 (-1175 1525)(-1175 1575);
WIRE 17 -1 (-1175 1475)(-1175 1525);
WIRE 17 -1 (-1175 1425)(-1175 1475);
WIRE 17 -1 (-1175 1375)(-1175 1425);
WIRE 17 -1 (-1175 1325)(-1175 1375);
WIRE 17 -1 (-1175 1275)(-1175 1325);
WIRE 17 -1 (-1175 1225)(-1175 1275);
WIRE 17 -1 (-1175 1175)(-1175 1225);
WIRE 17 -1 (-1175 1125)(-1175 1175);
WIRE 17 -1 (-1175 1075)(-1175 1125);
WIRE 17 -1 (-1175 1025)(-1175 1075);
WIRE 17 -1 (-1175 975)(-1175 1025);
WIRE 17 -1 (1575 2225)(1575 2325);
WIRE 17 -1 (1575 2325)(1575 2425);
WIRE 17 -1 (1575 2425)(1575 2525);
WIRE 17 -1 (1575 2625)(1575 2525);
WIRE 17 -1 (1575 2625)(1575 2725);
WIRE 17 -1 (1575 2725)(1575 2825);
WIRE 17 -1 (1575 2825)(1575 2925);
WIRE 17 -1 (1575 2925)(1575 3025);
WIRE 17 -1 (1575 3025)(1575 3125);
WIRE 17 -1 (1575 3125)(2600 3125);
FORCEPROP 2 LAST SIG_NAME M_C_CPU0_SB_DQS_DP<9:0>
J 0
(1815 3135);
DISPLAY 0.680851 (1815 3135);
PAINT WHITE (1815 3135);
WIRE 17 -1 (1575 3275)(1575 3375);
WIRE 17 -1 (1575 3375)(1575 3475);
WIRE 17 -1 (1575 3475)(1575 3575);
WIRE 17 -1 (1575 3675)(1575 3575);
WIRE 17 -1 (1575 3675)(1575 3775);
WIRE 17 -1 (1575 3775)(1575 3875);
WIRE 17 -1 (1575 3875)(1575 3975);
WIRE 17 -1 (1575 3975)(1575 4075);
WIRE 17 -1 (1575 4075)(1575 4175);
WIRE 17 -1 (1575 4175)(2600 4175);
FORCEPROP 2 LAST SIG_NAME M_C_CPU0_SA_DQS_DP<9:0>
J 0
(1815 4185);
DISPLAY 0.680851 (1815 4185);
PAINT WHITE (1815 4185);
WIRE 17 -1 (1750 2175)(1750 2275);
WIRE 17 -1 (1750 2275)(1750 2375);
WIRE 17 -1 (1750 2375)(1750 2475);
WIRE 17 -1 (1750 2575)(1750 2475);
WIRE 17 -1 (1750 2575)(1750 2675);
WIRE 17 -1 (1750 2675)(1750 2775);
WIRE 17 -1 (1750 2775)(1750 2875);
WIRE 17 -1 (1750 2875)(1750 2975);
WIRE 17 -1 (1750 2975)(1750 3075);
WIRE 17 -1 (1750 3075)(2600 3075);
FORCEPROP 2 LAST SIG_NAME M_C_CPU0_SB_DQS_DN<9:0>
J 0
(1815 3085);
DISPLAY 0.680851 (1815 3085);
PAINT WHITE (1815 3085);
WIRE 17 -1 (1750 3225)(1750 3325);
WIRE 17 -1 (1750 3325)(1750 3425);
WIRE 17 -1 (1750 3425)(1750 3525);
WIRE 17 -1 (1750 3625)(1750 3525);
WIRE 17 -1 (1750 3625)(1750 3725);
WIRE 17 -1 (1750 3725)(1750 3825);
WIRE 17 -1 (1750 3825)(1750 3925);
WIRE 17 -1 (1750 3925)(1750 4025);
WIRE 17 -1 (1750 4025)(1750 4125);
WIRE 17 -1 (1750 4125)(2600 4125);
FORCEPROP 2 LAST SIG_NAME M_C_CPU0_SA_DQS_DN<9:0>
J 0
(1815 4135);
DISPLAY 0.680851 (1815 4135);
PAINT WHITE (1815 4135);
WIRE 16 -1 (1500 550)(1500 500);
WIRE 16 -1 (-3700 1975)(-3700 1700);
WIRE 16 -1 (3200 4650)(3200 4150);
WIRE 16 -1 (500 375)(500 550);
WIRE 16 -1 (-2650 -175)(-2650 -100);
WIRE 16 -1 (4900 800)(4900 500);
WIRE 16 -1 (4900 850)(4900 800);
WIRE 16 -1 (4650 800)(4900 800);
WIRE 16 -1 (3200 500)(3200 900);
WIRE 16 -1 (2125 -50)(2125 25);
WIRE 16 -1 (500 175)(500 -50);
WIRE 16 3135 (150 775)(150 -525);
WIRE 16 3135 (2750 775)(150 775);
WIRE 16 3135 (150 -525)(2750 -525);
WIRE 16 3135 (2750 -525)(2750 775);
WIRE 16 -1 (1500 25)(1500 175);
WIRE 16 -1 (2125 25)(1500 25);
WIRE 16 -1 (2125 25)(2125 175);
WIRE 16 -1 (-2650 2850)(-3750 2850);
FORCEPROP 2 LAST SIG_NAME M_C_CPU0_CLK_DN<0>
J 0
(-3662 2859);
DISPLAY 0.680851 (-3662 2859);
PAINT WHITE (-3662 2859);
WIRE 16 -1 (-3700 1700)(-2650 1700);
WIRE 16 -1 (-2650 1650)(-3675 1650);
FORCEPROP 2 LAST SIG_NAME PD_CHC_CPU0_DIMM1_SAA
J 0
(-3685 1660);
DISPLAY 0.680851 (-3685 1660);
PAINT WHITE (-3685 1660);
WIRE 16 -1 (-2650 1600)(-3675 1600);
FORCEPROP 2 LAST SIG_NAME I3C_SPD_DDRABCD_CPU0_LVC1_SDA
J 0
(-3685 1610);
DISPLAY 0.680851 (-3685 1610);
PAINT WHITE (-3685 1610);
WIRE 16 -1 (-2650 1800)(-3750 1800);
FORCEPROP 2 LAST SIG_NAME M_C_CPU0_ALERT_N
J 0
(-3662 1809);
DISPLAY 0.680851 (-3662 1809);
PAINT WHITE (-3662 1809);
WIRE 16 -1 (-3025 1900)(-3750 1900);
FORCEPROP 2 LAST SIG_NAME RST_M_CD_CPU0_FPGA_N
J 0
(-3662 1909);
DISPLAY 0.680851 (-3662 1909);
PAINT WHITE (-3662 1909);
WIRE 16 -1 (-3025 1900)(-3025 1850);
WIRE 16 -1 (-3025 1850)(-2650 1850);
WIRE 16 -1 (-4200 1450)(-4025 1450);
WIRE 16 -1 (-4200 1550)(-4200 1450);
WIRE 16 -1 (-4200 1550)(-2650 1550);
FORCEPROP 2 LAST SIG_NAME I3C_SPD_DDRABCD_CPU0_LVC1_SCL_R5
J 0
(-3710 1560);
DISPLAY 0.680851 (-3710 1560);
PAINT WHITE (-3710 1560);
WIRE 16 -1 (-2600 1400)(-2650 1400);
WIRE 16 -1 (-2600 1450)(-2600 1400);
WIRE 16 -1 (-3825 1450)(-2600 1450);
FORCEPROP 2 LAST SIG_NAME I3C_SPD_DDRABCD_CPU0_LVC1_SCL
J 0
(-3710 1460);
DISPLAY 0.680851 (-3710 1460);
PAINT WHITE (-3710 1460);
WIRE 16 -1 (-2650 1300)(-3750 1300);
FORCEPROP 2 LAST SIG_NAME PWRGD_CHC_CPU0_DIMM1
J 0
(-3662 1309);
DISPLAY 0.680851 (-3662 1309);
PAINT WHITE (-3662 1309);
WIRE 16 -1 (-2650 1200)(-3750 1200);
FORCEPROP 2 LAST SIG_NAME TP_CHC_CPU0_DIMM1_FRU_6
J 0
(-3662 1209);
DISPLAY 0.680851 (-3662 1209);
PAINT WHITE (-3662 1209);
WIRE 16 -1 (-1450 2000)(-1275 2000);
WIRE 16 -1 (1375 4100)(1650 4100);
WIRE 16 -1 (1375 4000)(1650 4000);
WIRE 16 -1 (1375 3900)(1650 3900);
WIRE 16 -1 (1375 3800)(1650 3800);
WIRE 16 -1 (1375 3600)(1650 3600);
WIRE 16 -1 (1375 3700)(1650 3700);
WIRE 16 -1 (1375 3500)(1650 3500);
WIRE 16 -1 (1375 3400)(1650 3400);
WIRE 16 -1 (1375 3300)(1650 3300);
WIRE 16 -1 (1375 3200)(1650 3200);
WIRE 16 -1 (1375 2950)(1650 2950);
WIRE 16 -1 (1375 3050)(1650 3050);
WIRE 16 -1 (1375 2850)(1650 2850);
WIRE 16 -1 (1375 2750)(1650 2750);
WIRE 16 -1 (1375 2650)(1650 2650);
WIRE 16 -1 (1375 2550)(1650 2550);
WIRE 16 -1 (1375 2450)(1650 2450);
WIRE 16 -1 (1375 2350)(1650 2350);
WIRE 16 -1 (1375 2250)(1650 2250);
WIRE 16 -1 (1375 2150)(1650 2150);
WIRE 16 -1 (1375 4150)(1475 4150);
WIRE 16 -1 (1375 4050)(1475 4050);
WIRE 16 -1 (1375 3950)(1475 3950);
WIRE 16 -1 (1375 3850)(1475 3850);
WIRE 16 -1 (1375 3750)(1475 3750);
WIRE 16 -1 (1375 3650)(1475 3650);
WIRE 16 -1 (1375 3550)(1475 3550);
WIRE 16 -1 (1375 3450)(1475 3450);
WIRE 16 -1 (1375 3350)(1475 3350);
WIRE 16 -1 (1375 3250)(1475 3250);
WIRE 16 -1 (1375 3100)(1475 3100);
WIRE 16 -1 (1375 3000)(1475 3000);
WIRE 16 -1 (1375 2900)(1475 2900);
WIRE 16 -1 (1375 2800)(1475 2800);
WIRE 16 -1 (1375 2700)(1475 2700);
WIRE 16 -1 (1375 2600)(1475 2600);
WIRE 16 -1 (1375 2500)(1475 2500);
WIRE 16 -1 (1375 2400)(1475 2400);
WIRE 16 -1 (1375 2300)(1475 2300);
WIRE 16 -1 (1375 2200)(1475 2200);
WIRE 16 -1 (-1450 3500)(-1275 3500);
WIRE 16 -1 (-1450 3250)(-1275 3250);
WIRE 16 -1 (-2650 3000)(-3750 3000);
FORCEPROP 2 LAST SIG_NAME M_C_CPU0_SB_CS_N<0>
J 0
(-3662 3009);
DISPLAY 0.680851 (-3662 3009);
PAINT WHITE (-3662 3009);
WIRE 16 -1 (-2825 2250)(-2650 2250);
WIRE 16 -1 (3450 4150)(3200 4150);
WIRE 16 -1 (3200 4150)(3200 4100);
WIRE 16 -1 (3200 4100)(3450 4100);
WIRE 16 -1 (3200 4100)(3200 4050);
WIRE 16 -1 (3450 4050)(3200 4050);
WIRE 16 -1 (-1450 3550)(-1275 3550);
WIRE 16 -1 (-2650 3050)(-3750 3050);
FORCEPROP 2 LAST SIG_NAME M_C_CPU0_SB_CS_N<1>
J 0
(-3662 3059);
DISPLAY 0.680851 (-3662 3059);
PAINT WHITE (-3662 3059);
WIRE 16 -1 (-2825 3500)(-2650 3500);
WIRE 16 -1 (-2825 3450)(-2650 3450);
WIRE 16 -1 (-1450 3050)(-1275 3050);
WIRE 16 -1 (3450 4000)(3200 4000);
WIRE 16 -1 (3200 3950)(3200 4000);
WIRE 16 -1 (3200 3950)(3450 3950);
WIRE 16 -1 (3200 3900)(3200 3950);
WIRE 16 -1 (3450 3900)(3200 3900);
WIRE 16 -1 (3200 3850)(3200 3900);
WIRE 16 -1 (3200 3850)(3450 3850);
WIRE 16 -1 (3200 3800)(3200 3850);
WIRE 16 -1 (3200 3800)(3450 3800);
WIRE 16 -1 (3200 3750)(3200 3800);
WIRE 16 -1 (3200 3750)(3450 3750);
WIRE 16 -1 (3200 3700)(3200 3750);
WIRE 16 -1 (3200 3700)(3450 3700);
WIRE 16 -1 (3200 3650)(3200 3700);
WIRE 16 -1 (3200 3650)(3450 3650);
WIRE 16 -1 (3200 3600)(3200 3650);
WIRE 16 -1 (3200 3600)(3450 3600);
WIRE 16 -1 (3200 3550)(3450 3550);
WIRE 16 -1 (3200 3550)(3200 3600);
WIRE 16 -1 (3200 3500)(3200 3550);
WIRE 16 -1 (3200 3500)(3450 3500);
WIRE 16 -1 (3200 3450)(3200 3500);
WIRE 16 -1 (3200 3450)(3450 3450);
WIRE 16 -1 (3200 3400)(3200 3450);
WIRE 16 -1 (3450 3400)(3200 3400);
WIRE 16 -1 (3200 3350)(3200 3400);
WIRE 16 -1 (3200 3350)(3450 3350);
WIRE 16 -1 (3200 3300)(3200 3350);
WIRE 16 -1 (3200 3300)(3450 3300);
WIRE 16 -1 (3200 3250)(3200 3300);
WIRE 16 -1 (3200 3250)(3450 3250);
WIRE 16 -1 (3200 3200)(3200 3250);
WIRE 16 -1 (3200 3200)(3450 3200);
WIRE 16 -1 (3200 3150)(3200 3200);
WIRE 16 -1 (3200 3150)(3450 3150);
WIRE 16 -1 (3200 3100)(3200 3150);
WIRE 16 -1 (3200 3100)(3450 3100);
WIRE 16 -1 (3200 3050)(3450 3050);
WIRE 16 -1 (3200 3050)(3200 3100);
WIRE 16 -1 (3200 3000)(3200 3050);
WIRE 16 -1 (3200 3000)(3450 3000);
WIRE 16 -1 (3200 2950)(3200 3000);
WIRE 16 -1 (3200 2950)(3450 2950);
WIRE 16 -1 (3200 2900)(3200 2950);
WIRE 16 -1 (3450 2900)(3200 2900);
WIRE 16 -1 (3200 2850)(3200 2900);
WIRE 16 -1 (3200 2850)(3450 2850);
WIRE 16 -1 (3200 2800)(3200 2850);
WIRE 16 -1 (3200 2800)(3450 2800);
WIRE 16 -1 (3200 2750)(3200 2800);
WIRE 16 -1 (3200 2750)(3450 2750);
WIRE 16 -1 (3200 2700)(3200 2750);
WIRE 16 -1 (3200 2700)(3450 2700);
WIRE 16 -1 (3200 2650)(3200 2700);
WIRE 16 -1 (3200 2650)(3450 2650);
WIRE 16 -1 (3200 2600)(3200 2650);
WIRE 16 -1 (3200 2600)(3450 2600);
WIRE 16 -1 (3200 2550)(3450 2550);
WIRE 16 -1 (3200 2550)(3200 2600);
WIRE 16 -1 (3200 2500)(3200 2550);
WIRE 16 -1 (3200 2500)(3450 2500);
WIRE 16 -1 (3200 2450)(3200 2500);
WIRE 16 -1 (3200 2450)(3450 2450);
WIRE 16 -1 (3200 2400)(3200 2450);
WIRE 16 -1 (3450 2400)(3200 2400);
WIRE 16 -1 (3200 2350)(3200 2400);
WIRE 16 -1 (3200 2350)(3450 2350);
WIRE 16 -1 (3200 2300)(3200 2350);
WIRE 16 -1 (3200 2300)(3450 2300);
WIRE 16 -1 (3200 2250)(3200 2300);
WIRE 16 -1 (3200 2250)(3450 2250);
WIRE 16 -1 (3200 2200)(3200 2250);
WIRE 16 -1 (3200 2200)(3450 2200);
WIRE 16 -1 (3200 2150)(3200 2200);
WIRE 16 -1 (3200 2150)(3450 2150);
WIRE 16 -1 (3200 2100)(3200 2150);
WIRE 16 -1 (3200 2100)(3450 2100);
WIRE 16 -1 (3200 2050)(3200 2100);
WIRE 16 -1 (3200 2050)(3450 2050);
WIRE 16 -1 (3200 2000)(3450 2000);
WIRE 16 -1 (3200 2000)(3200 2050);
WIRE 16 -1 (3200 1950)(3200 2000);
WIRE 16 -1 (3200 1950)(3450 1950);
WIRE 16 -1 (3200 1900)(3200 1950);
WIRE 16 -1 (3450 1900)(3200 1900);
WIRE 16 -1 (3200 1850)(3200 1900);
WIRE 16 -1 (3200 1850)(3450 1850);
WIRE 16 -1 (3200 1800)(3200 1850);
WIRE 16 -1 (3200 1800)(3450 1800);
WIRE 16 -1 (3200 1750)(3200 1800);
WIRE 16 -1 (3200 1750)(3450 1750);
WIRE 16 -1 (3200 1700)(3200 1750);
WIRE 16 -1 (3200 1700)(3450 1700);
WIRE 16 -1 (3200 1650)(3200 1700);
WIRE 16 -1 (3200 1650)(3450 1650);
WIRE 16 -1 (3200 1600)(3200 1650);
WIRE 16 -1 (3200 1600)(3450 1600);
WIRE 16 -1 (3200 1550)(3200 1600);
WIRE 16 -1 (3200 1550)(3450 1550);
WIRE 16 -1 (3200 1500)(3450 1500);
WIRE 16 -1 (3200 1500)(3200 1550);
WIRE 16 -1 (3200 1450)(3200 1500);
WIRE 16 -1 (3200 1450)(3450 1450);
WIRE 16 -1 (3200 1400)(3200 1450);
WIRE 16 -1 (3450 1400)(3200 1400);
WIRE 16 -1 (3200 1350)(3200 1400);
WIRE 16 -1 (3200 1350)(3450 1350);
WIRE 16 -1 (3200 1300)(3200 1350);
WIRE 16 -1 (3200 1300)(3450 1300);
WIRE 16 -1 (3200 1250)(3200 1300);
WIRE 16 -1 (3200 1250)(3450 1250);
WIRE 16 -1 (3200 1200)(3200 1250);
WIRE 16 -1 (3200 1200)(3450 1200);
WIRE 16 -1 (3200 1150)(3200 1200);
WIRE 16 -1 (3200 1150)(3450 1150);
WIRE 16 -1 (3200 1100)(3200 1150);
WIRE 16 -1 (3200 1100)(3450 1100);
WIRE 16 -1 (3200 1050)(3200 1100);
WIRE 16 -1 (3200 1050)(3450 1050);
WIRE 16 -1 (3200 1000)(3450 1000);
WIRE 16 -1 (3200 1000)(3200 1050);
WIRE 16 -1 (3200 950)(3200 1000);
WIRE 16 -1 (3200 950)(3450 950);
WIRE 16 -1 (3200 900)(3200 950);
WIRE 16 -1 (3200 900)(3450 900);
WIRE 16 -1 (-1450 2500)(-1275 2500);
WIRE 16 -1 (-1450 2400)(-1275 2400);
WIRE 16 -1 (4650 4150)(4900 4150);
WIRE 16 -1 (4650 4100)(4900 4100);
WIRE 16 -1 (4900 4150)(4900 4100);
WIRE 16 -1 (4650 4050)(4900 4050);
WIRE 16 -1 (4900 4100)(4900 4050);
WIRE 16 -1 (4650 4000)(4900 4000);
WIRE 16 -1 (4900 4050)(4900 4000);
WIRE 16 -1 (4650 3950)(4900 3950);
WIRE 16 -1 (4900 4000)(4900 3950);
WIRE 16 -1 (4650 3900)(4900 3900);
WIRE 16 -1 (4900 3950)(4900 3900);
WIRE 16 -1 (4650 3850)(4900 3850);
WIRE 16 -1 (4900 3900)(4900 3850);
WIRE 16 -1 (4650 3800)(4900 3800);
WIRE 16 -1 (4900 3850)(4900 3800);
WIRE 16 -1 (4650 3750)(4900 3750);
WIRE 16 -1 (4900 3800)(4900 3750);
WIRE 16 -1 (4650 3700)(4900 3700);
WIRE 16 -1 (4900 3750)(4900 3700);
WIRE 16 -1 (4650 3650)(4900 3650);
WIRE 16 -1 (4900 3700)(4900 3650);
WIRE 16 -1 (4650 3600)(4900 3600);
WIRE 16 -1 (4900 3650)(4900 3600);
WIRE 16 -1 (4650 3550)(4900 3550);
WIRE 16 -1 (4900 3600)(4900 3550);
WIRE 16 -1 (4650 3500)(4900 3500);
WIRE 16 -1 (4900 3550)(4900 3500);
WIRE 16 -1 (4650 3450)(4900 3450);
WIRE 16 -1 (4900 3500)(4900 3450);
WIRE 16 -1 (4650 3400)(4900 3400);
WIRE 16 -1 (4900 3400)(4900 3450);
WIRE 16 -1 (4650 3350)(4900 3350);
WIRE 16 -1 (4900 3400)(4900 3350);
WIRE 16 -1 (4900 3300)(4650 3300);
WIRE 16 -1 (4900 3350)(4900 3300);
WIRE 16 -1 (4900 3250)(4650 3250);
WIRE 16 -1 (4900 3300)(4900 3250);
WIRE 16 -1 (4650 3200)(4900 3200);
WIRE 16 -1 (4900 3250)(4900 3200);
WIRE 16 -1 (4650 3150)(4900 3150);
WIRE 16 -1 (4900 3200)(4900 3150);
WIRE 16 -1 (4650 3100)(4900 3100);
WIRE 16 -1 (4900 3150)(4900 3100);
WIRE 16 -1 (4650 3050)(4900 3050);
WIRE 16 -1 (4900 3100)(4900 3050);
WIRE 16 -1 (4650 3000)(4900 3000);
WIRE 16 -1 (4900 3050)(4900 3000);
WIRE 16 -1 (4650 2950)(4900 2950);
WIRE 16 -1 (4900 3000)(4900 2950);
WIRE 16 -1 (4650 2900)(4900 2900);
WIRE 16 -1 (4900 2900)(4900 2950);
WIRE 16 -1 (4650 2850)(4900 2850);
WIRE 16 -1 (4900 2900)(4900 2850);
WIRE 16 -1 (4900 2800)(4650 2800);
WIRE 16 -1 (4900 2850)(4900 2800);
WIRE 16 -1 (4900 2750)(4650 2750);
WIRE 16 -1 (4900 2800)(4900 2750);
WIRE 16 -1 (4650 2700)(4900 2700);
WIRE 16 -1 (4900 2750)(4900 2700);
WIRE 16 -1 (4650 2650)(4900 2650);
WIRE 16 -1 (4900 2700)(4900 2650);
WIRE 16 -1 (4650 2600)(4900 2600);
WIRE 16 -1 (4900 2650)(4900 2600);
WIRE 16 -1 (4650 2550)(4900 2550);
WIRE 16 -1 (4900 2600)(4900 2550);
WIRE 16 -1 (4650 2500)(4900 2500);
WIRE 16 -1 (4900 2550)(4900 2500);
WIRE 16 -1 (4650 2450)(4900 2450);
WIRE 16 -1 (4900 2500)(4900 2450);
WIRE 16 -1 (4650 2400)(4900 2400);
WIRE 16 -1 (4900 2400)(4900 2450);
WIRE 16 -1 (4650 2350)(4900 2350);
WIRE 16 -1 (4900 2400)(4900 2350);
WIRE 16 -1 (4900 2300)(4650 2300);
WIRE 16 -1 (4900 2350)(4900 2300);
WIRE 16 -1 (4900 2250)(4650 2250);
WIRE 16 -1 (4900 2300)(4900 2250);
WIRE 16 -1 (4650 2200)(4900 2200);
WIRE 16 -1 (4900 2250)(4900 2200);
WIRE 16 -1 (4650 2150)(4900 2150);
WIRE 16 -1 (4900 2200)(4900 2150);
WIRE 16 -1 (4650 2100)(4900 2100);
WIRE 16 -1 (4900 2150)(4900 2100);
WIRE 16 -1 (4650 2050)(4900 2050);
WIRE 16 -1 (4900 2100)(4900 2050);
WIRE 16 -1 (4650 2000)(4900 2000);
WIRE 16 -1 (4900 2050)(4900 2000);
WIRE 16 -1 (4650 1950)(4900 1950);
WIRE 16 -1 (4900 2000)(4900 1950);
WIRE 16 -1 (4650 1900)(4900 1900);
WIRE 16 -1 (4900 1900)(4900 1950);
WIRE 16 -1 (4650 1850)(4900 1850);
WIRE 16 -1 (4900 1900)(4900 1850);
WIRE 16 -1 (4900 1800)(4650 1800);
WIRE 16 -1 (4900 1850)(4900 1800);
WIRE 16 -1 (4900 1750)(4650 1750);
WIRE 16 -1 (4900 1800)(4900 1750);
WIRE 16 -1 (4900 1700)(4650 1700);
WIRE 16 -1 (4900 1750)(4900 1700);
WIRE 16 -1 (4900 1650)(4650 1650);
WIRE 16 -1 (4900 1700)(4900 1650);
WIRE 16 -1 (4650 1600)(4900 1600);
WIRE 16 -1 (4900 1600)(4900 1650);
WIRE 16 -1 (4900 1550)(4650 1550);
WIRE 16 -1 (4900 1550)(4900 1600);
WIRE 16 -1 (4900 1500)(4650 1500);
WIRE 16 -1 (4900 1550)(4900 1500);
WIRE 16 -1 (4900 1450)(4650 1450);
WIRE 16 -1 (4900 1500)(4900 1450);
WIRE 16 -1 (4650 1400)(4900 1400);
WIRE 16 -1 (4900 1450)(4900 1400);
WIRE 16 -1 (4650 1350)(4900 1350);
WIRE 16 -1 (4900 1400)(4900 1350);
WIRE 16 -1 (4650 1300)(4900 1300);
WIRE 16 -1 (4900 1350)(4900 1300);
WIRE 16 -1 (4650 1250)(4900 1250);
WIRE 16 -1 (4900 1300)(4900 1250);
WIRE 16 -1 (4650 1200)(4900 1200);
WIRE 16 -1 (4900 1250)(4900 1200);
WIRE 16 -1 (4650 1150)(4900 1150);
WIRE 16 -1 (4900 1200)(4900 1150);
WIRE 16 -1 (4650 1100)(4900 1100);
WIRE 16 -1 (4900 1150)(4900 1100);
WIRE 16 -1 (4650 1050)(4900 1050);
WIRE 16 -1 (4900 1050)(4900 1100);
WIRE 16 -1 (4650 1000)(4900 1000);
WIRE 16 -1 (4900 1050)(4900 1000);
WIRE 16 -1 (4650 900)(4900 900);
WIRE 16 -1 (4900 1000)(4900 900);
WIRE 16 -1 (4900 900)(4900 850);
WIRE 16 -1 (4650 850)(4900 850);
WIRE 16 -1 (-1450 1050)(-1275 1050);
WIRE 16 -1 (-1450 1300)(-1275 1300);
WIRE 16 -1 (-1450 1350)(-1275 1350);
WIRE 16 -1 (-1450 1400)(-1275 1400);
WIRE 16 -1 (-1450 1450)(-1275 1450);
WIRE 16 -1 (-2650 900)(-3750 900);
FORCEPROP 2 LAST SIG_NAME TP_CHC_CPU0_DIMM1_FRU_0
J 0
(-3662 909);
DISPLAY 0.680851 (-3662 909);
PAINT WHITE (-3662 909);
WIRE 16 -1 (-2650 950)(-3750 950);
FORCEPROP 2 LAST SIG_NAME TP_CHC_CPU0_DIMM1_FRU_1
J 0
(-3662 959);
DISPLAY 0.680851 (-3662 959);
PAINT WHITE (-3662 959);
WIRE 16 -1 (-2650 1000)(-3750 1000);
FORCEPROP 2 LAST SIG_NAME TP_CHC_CPU0_DIMM1_FRU_2
J 0
(-3662 1009);
DISPLAY 0.680851 (-3662 1009);
PAINT WHITE (-3662 1009);
WIRE 16 -1 (-2650 1050)(-3750 1050);
FORCEPROP 2 LAST SIG_NAME TP_CHC_CPU0_DIMM1_FRU_3
J 0
(-3662 1059);
DISPLAY 0.680851 (-3662 1059);
PAINT WHITE (-3662 1059);
WIRE 16 -1 (-2650 1100)(-3750 1100);
FORCEPROP 2 LAST SIG_NAME TP_CHC_CPU0_DIMM1_FRU_4
J 0
(-3662 1109);
DISPLAY 0.680851 (-3662 1109);
PAINT WHITE (-3662 1109);
WIRE 16 -1 (-2650 1150)(-3750 1150);
FORCEPROP 2 LAST SIG_NAME TP_CHC_CPU0_DIMM1_FRU_5
J 0
(-3662 1159);
DISPLAY 0.680851 (-3662 1159);
PAINT WHITE (-3662 1159);
WIRE 16 -1 (-2650 3300)(-3750 3300);
FORCEPROP 2 LAST SIG_NAME M_C_CPU0_SB_PAR
J 0
(-3662 3309);
DISPLAY 0.680851 (-3662 3309);
PAINT WHITE (-3662 3309);
WIRE 16 -1 (-2650 3350)(-3750 3350);
FORCEPROP 2 LAST SIG_NAME M_C_CPU0_SA_PAR
J 0
(-3662 3359);
DISPLAY 0.680851 (-3662 3359);
PAINT WHITE (-3662 3359);
WIRE 16 -1 (-2650 700)(-3750 700);
FORCEPROP 2 LAST SIG_NAME M_C_CPU0_SB_RSP<0>
J 0
(-3662 709);
DISPLAY 0.680851 (-3662 709);
PAINT WHITE (-3662 709);
WIRE 16 -1 (-2650 750)(-3750 750);
FORCEPROP 2 LAST SIG_NAME M_C_CPU0_SA_RSP<0>
J 0
(-3662 759);
DISPLAY 0.680851 (-3662 759);
PAINT WHITE (-3662 759);
WIRE 16 -1 (-1450 950)(-1275 950);
WIRE 16 -1 (-1450 1000)(-1275 1000);
WIRE 16 -1 (-1450 1100)(-1275 1100);
WIRE 16 -1 (-1450 1150)(-1275 1150);
WIRE 16 -1 (-1450 1200)(-1275 1200);
WIRE 16 -1 (-1450 1250)(-1275 1250);
WIRE 16 -1 (-1450 1500)(-1275 1500);
WIRE 16 -1 (-1450 1550)(-1275 1550);
WIRE 16 -1 (-1450 1600)(-1275 1600);
WIRE 16 -1 (-1450 1650)(-1275 1650);
WIRE 16 -1 (-1450 1700)(-1275 1700);
WIRE 16 -1 (-1450 1750)(-1275 1750);
WIRE 16 -1 (-1450 1800)(-1275 1800);
WIRE 16 -1 (-1450 1850)(-1275 1850);
WIRE 16 -1 (-1450 1900)(-1275 1900);
WIRE 16 -1 (-1450 1950)(-1275 1950);
WIRE 16 -1 (-1450 2050)(-1275 2050);
WIRE 16 -1 (-1450 2100)(-1275 2100);
WIRE 16 -1 (-1450 2150)(-1275 2150);
WIRE 16 -1 (-1450 2200)(-1275 2200);
WIRE 16 -1 (-1450 2250)(-1275 2250);
WIRE 16 -1 (-1450 2300)(-1275 2300);
WIRE 16 -1 (-1450 2350)(-1275 2350);
WIRE 16 -1 (-1450 2450)(-1275 2450);
WIRE 16 -1 (-1450 2600)(-1275 2600);
WIRE 16 -1 (-1450 2650)(-1275 2650);
WIRE 16 -1 (-1450 2700)(-1275 2700);
WIRE 16 -1 (-1450 2750)(-1275 2750);
WIRE 16 -1 (-1450 2800)(-1275 2800);
WIRE 16 -1 (-1450 2850)(-1275 2850);
WIRE 16 -1 (-1450 2900)(-1275 2900);
WIRE 16 -1 (-1450 2950)(-1275 2950);
WIRE 16 -1 (-1450 3000)(-1275 3000);
WIRE 16 -1 (-1450 3100)(-1275 3100);
WIRE 16 -1 (-1450 3150)(-1275 3150);
WIRE 16 -1 (-1450 3200)(-1275 3200);
WIRE 16 -1 (-1450 3300)(-1275 3300);
WIRE 16 -1 (-1450 3350)(-1275 3350);
WIRE 16 -1 (-1450 3400)(-1275 3400);
WIRE 16 -1 (-1450 3450)(-1275 3450);
WIRE 16 -1 (-1450 3600)(-1275 3600);
WIRE 16 -1 (-1450 3650)(-1275 3650);
WIRE 16 -1 (-1450 3700)(-1275 3700);
WIRE 16 -1 (-1450 3750)(-1275 3750);
WIRE 16 -1 (-1450 3800)(-1275 3800);
WIRE 16 -1 (-1450 3850)(-1275 3850);
WIRE 16 -1 (-1450 3900)(-1275 3900);
WIRE 16 -1 (-1450 3950)(-1275 3950);
WIRE 16 -1 (-1450 4000)(-1275 4000);
WIRE 16 -1 (-1450 4050)(-1275 4050);
WIRE 16 -1 (-1450 4100)(-1275 4100);
WIRE 16 -1 (-2650 3200)(-3750 3200);
FORCEPROP 2 LAST SIG_NAME M_C_CPU0_SA_CS_N<1>
J 0
(-3662 3209);
DISPLAY 0.680851 (-3662 3209);
PAINT WHITE (-3662 3209);
WIRE 16 -1 (-2650 3150)(-3750 3150);
FORCEPROP 2 LAST SIG_NAME M_C_CPU0_SA_CS_N<0>
J 0
(-3662 3159);
DISPLAY 0.680851 (-3662 3159);
PAINT WHITE (-3662 3159);
WIRE 16 -1 (-2650 2900)(-3750 2900);
FORCEPROP 2 LAST SIG_NAME M_C_CPU0_CLK_DP<0>
J 0
(-3662 2909);
DISPLAY 0.680851 (-3662 2909);
PAINT WHITE (-3662 2909);
WIRE 16 -1 (-2825 1950)(-2650 1950);
WIRE 16 -1 (-2825 2000)(-2650 2000);
WIRE 16 -1 (-2825 2050)(-2650 2050);
WIRE 16 -1 (-2825 2100)(-2650 2100);
WIRE 16 -1 (-2825 2150)(-2650 2150);
WIRE 16 -1 (-2825 2200)(-2650 2200);
WIRE 16 -1 (-2825 2400)(-2650 2400);
WIRE 16 -1 (-2825 2500)(-2650 2500);
WIRE 16 -1 (-2825 2550)(-2650 2550);
WIRE 16 -1 (-2825 2650)(-2650 2650);
WIRE 16 -1 (-2825 2700)(-2650 2700);
WIRE 16 -1 (-2825 3750)(-2650 3750);
WIRE 16 -1 (-2825 4150)(-2650 4150);
WIRE 16 -1 (-2825 3700)(-2650 3700);
WIRE 16 -1 (-2825 4100)(-2650 4100);
WIRE 16 -1 (-2825 3650)(-2650 3650);
WIRE 16 -1 (-2825 4050)(-2650 4050);
WIRE 16 -1 (-2825 3600)(-2650 3600);
WIRE 16 -1 (-2825 4000)(-2650 4000);
WIRE 16 -1 (-2825 3550)(-2650 3550);
WIRE 16 -1 (-2825 3950)(-2650 3950);
WIRE 16 -1 (-2825 3900)(-2650 3900);
WIRE 16 -1 (-2825 3850)(-2650 3850);
WIRE 16 -1 (-2825 2300)(-2650 2300);
WIRE 16 -1 (-2825 2450)(-2650 2450);
WIRE 16 -1 (-2825 2600)(-2650 2600);
WIRE 16 -1 (-2825 2750)(-2650 2750);
WIRE 16 -1 (-1450 4150)(-1275 4150);
WIRE 16 -1 (-2650 200)(-3750 200);
FORCEPROP 2 LAST SIG_NAME PD_CHC_CPU0_DIMM1_SAA
J 0
(-3662 209);
DISPLAY 0.680851 (-3662 209);
PAINT WHITE (-3662 209);
WIRE 16 -1 (-2650 100)(-2650 200);
WIRE 16 -1 (1500 500)(1500 375);
WIRE 16 -1 (2125 500)(1500 500);
WIRE 16 -1 (2125 375)(2125 500);
DOT 1 (3200 2450);
DOT 1 (3200 2500);
DOT 1 (3200 2600);
DOT 1 (3200 2050);
DOT 1 (3200 2650);
DOT 1 (4900 800);
DOT 1 (4900 850);
DOT 1 (4900 900);
DOT 1 (1500 500);
DOT 1 (2125 25);
DOT 1 (3200 1000);
DOT 1 (3200 950);
DOT 1 (3200 900);
DOT 1 (3200 1200);
DOT 1 (3200 1150);
DOT 1 (3200 1050);
DOT 1 (3200 1100);
DOT 1 (3200 1250);
DOT 1 (3200 1500);
DOT 1 (3200 1400);
DOT 1 (3200 1350);
DOT 1 (3200 1300);
DOT 1 (3200 1450);
DOT 1 (3200 1700);
DOT 1 (3200 1650);
DOT 1 (3200 1550);
DOT 1 (3200 1600);
DOT 1 (3200 1750);
DOT 1 (3200 1800);
DOT 1 (3200 2000);
DOT 1 (3200 1900);
DOT 1 (3200 1850);
DOT 1 (3200 1950);
DOT 1 (3200 2250);
DOT 1 (3200 2100);
DOT 1 (3200 2150);
DOT 1 (3200 2200);
DOT 1 (3200 2300);
DOT 1 (3200 2400);
DOT 1 (3200 2350);
DOT 1 (3200 2550);
DOT 1 (3200 2750);
DOT 1 (3200 2700);
DOT 1 (3200 2800);
DOT 1 (3200 3000);
DOT 1 (3200 2950);
DOT 1 (3200 2900);
DOT 1 (3200 2850);
DOT 1 (3200 3050);
DOT 1 (3200 3250);
DOT 1 (3200 3200);
DOT 1 (3200 3100);
DOT 1 (3200 3150);
DOT 1 (3200 3300);
DOT 1 (3200 3500);
DOT 1 (3200 3450);
DOT 1 (3200 3400);
DOT 1 (3200 3350);
DOT 1 (3200 3550);
DOT 1 (3200 3750);
DOT 1 (3200 3600);
DOT 1 (3200 3650);
DOT 1 (3200 3700);
DOT 1 (3200 3800);
DOT 1 (3200 3850);
DOT 1 (3200 3950);
DOT 1 (3200 3900);
DOT 1 (3200 4100);
DOT 1 (3200 4150);
DOT 1 (4900 1000);
DOT 1 (4900 1050);
DOT 1 (4900 1100);
DOT 1 (4900 1150);
DOT 1 (4900 1200);
DOT 1 (4900 1250);
DOT 1 (4900 1300);
DOT 1 (4900 1350);
DOT 1 (4900 1400);
DOT 1 (4900 1450);
DOT 1 (4900 1500);
DOT 1 (4900 1550);
DOT 1 (4900 1600);
DOT 1 (4900 1650);
DOT 1 (4900 1700);
DOT 1 (4900 1750);
DOT 1 (4900 1800);
DOT 1 (4900 1850);
DOT 1 (4900 1900);
DOT 1 (4900 1950);
DOT 1 (4900 2000);
DOT 1 (4900 2050);
DOT 1 (4900 2100);
DOT 1 (4900 2150);
DOT 1 (4900 2200);
DOT 1 (4900 2250);
DOT 1 (4900 2300);
DOT 1 (4900 2400);
DOT 1 (4900 2350);
DOT 1 (4900 2450);
DOT 1 (4900 2500);
DOT 1 (4900 2550);
DOT 1 (4900 2650);
DOT 1 (4900 2600);
DOT 1 (4900 2700);
DOT 1 (4900 2750);
DOT 1 (4900 2800);
DOT 1 (4900 2850);
DOT 1 (4900 2900);
DOT 1 (4900 2950);
DOT 1 (4900 3000);
DOT 1 (4900 3050);
DOT 1 (4900 3200);
DOT 1 (4900 3100);
DOT 1 (4900 3150);
DOT 1 (4900 3250);
DOT 1 (4900 3300);
DOT 1 (4900 3350);
DOT 1 (4900 3400);
DOT 1 (4900 3450);
DOT 1 (4900 3500);
DOT 1 (4900 3550);
DOT 1 (4900 3600);
DOT 1 (4900 3650);
DOT 1 (4900 3700);
DOT 1 (4900 3750);
DOT 1 (4900 3800);
DOT 1 (4900 3850);
DOT 1 (4900 3900);
DOT 1 (4900 3950);
DOT 1 (4900 4000);
DOT 1 (4900 4050);
DOT 1 (4900 4100);
FORCENOTE
20210728 MODIFY FOR GT
(-4150 4800) 0;
DISPLAY LEFT (-4150 4800);
DISPLAY 2.510638 (-4150 4800);
PAINT PINK (-4150 4800);
QUIT
